G04 ================== begin FILE IDENTIFICATION RECORD ==================*
G04 Layout Name:  D:/<user>/Wistron_project/16317-1/gbr/16317-1.brd*
G04 Film Name:    L2GND*
G04 File Format:  Gerber RS274X*
G04 File Origin:  Cadence Allegro 16.5-S056*
G04 Origin Date:  Fri Jun 09 15:53:20 2017*
G04 *
G04 Layer:  VIA CLASS/L2GND*
G04 Layer:  PIN/L2GND*
G04 Layer:  ETCH/L2GND*
G04 Layer:  DRAWING FORMAT/LAYER_PCB_STORY*
G04 Layer:  DRAWING FORMAT/LAYER_L2GND*
G04 *
G04 Offset:    (0.00 0.00)*
G04 Mirror:    No*
G04 Mode:      Negative*
G04 Rotation:  0*
G04 FullContactRelief:  No*
G04 UndefLineWidth:     6.00*
G04 ================== end FILE IDENTIFICATION RECORD ====================*
%FSLAX35Y35*MOIN*%
%IR0*IPPOS*OFA0.00000B0.00000*MIA0B0*SFA1.00000B1.00000*%
%ADD36C,.04*%
%ADD12C,.032*%
%ADD35C,.043*%
%ADD23C,.081*%
%ADD16C,.063*%
%ADD15C,.036*%
%ADD21C,.065*%
%ADD19C,.038*%
%ADD37C,.058*%
%AMMACRO33*
4,1,14,.0447,.02349,
.0481,.015371,
.050038,.006785,
.050456,-.002007,
.049341,-.010738,
.046727,-.019143,
.0447,-.02349,
.04839,-.02718,
.052375,-.018364,
.054768,-.00899,
.055497,.000656,
.05454,.010283,
.051926,.019598,
.04839,.02718,
.0447,.02349,
180.*
4,1,14,.02349,-.0447,
.015371,-.0481,
.006785,-.050038,
-.002007,-.050456,
-.010738,-.049341,
-.019143,-.046727,
-.02349,-.0447,
-.02718,-.04839,
-.018364,-.052375,
-.00899,-.054768,
.000656,-.055497,
.010283,-.05454,
.019598,-.051926,
.02718,-.04839,
.02349,-.0447,
180.*
4,1,14,-.0447,-.02349,
-.0481,-.015371,
-.050038,-.006785,
-.050456,.002007,
-.049341,.010738,
-.046727,.019143,
-.0447,.02349,
-.04839,.02718,
-.052375,.018364,
-.054768,.00899,
-.055497,-.000656,
-.05454,-.010283,
-.051926,-.019598,
-.04839,-.02718,
-.0447,-.02349,
180.*
4,1,14,-.02349,.0447,
-.015371,.0481,
-.006785,.050038,
.002007,.050456,
.010738,.049341,
.019143,.046727,
.02349,.0447,
.02718,.04839,
.018364,.052375,
.00899,.054768,
-.000656,.055497,
-.010283,.05454,
-.019598,.051926,
-.02718,.04839,
-.02349,.0447,
180.*
%
%ADD33MACRO33*%
%AMMACRO20*
4,1,15,.00398,.00044,
.003999,.000208,
.004004,-.000025,
.003996,-.000258,
.00398,-.00044,
.00483,-.00129,
.004897,-.001007,
.004947,-.000721,
.004981,-.000432,
.004997,-.000141,
.004997,.000149,
.00498,.00044,
.004946,.000729,
.004895,.001015,
.00483,.00129,
.00398,.00044,
90.*
4,1,15,.00044,-.00398,
.000208,-.003999,
-.000025,-.004004,
-.000258,-.003996,
-.00044,-.00398,
-.00129,-.00483,
-.001007,-.004897,
-.000721,-.004947,
-.000432,-.004981,
-.000141,-.004997,
.000149,-.004997,
.00044,-.00498,
.000729,-.004946,
.001015,-.004895,
.00129,-.00483,
.00044,-.00398,
90.*
4,1,15,-.00398,-.00044,
-.003999,-.000208,
-.004004,.000025,
-.003996,.000258,
-.00398,.00044,
-.00483,.00129,
-.004897,.001007,
-.004947,.000721,
-.004981,.000432,
-.004997,.000141,
-.004997,-.000149,
-.00498,-.00044,
-.004946,-.000729,
-.004895,-.001015,
-.00483,-.00129,
-.00398,-.00044,
90.*
4,1,15,-.00044,.00398,
-.000208,.003999,
.000025,.004004,
.000258,.003996,
.00044,.00398,
.00129,.00483,
.001007,.004897,
.000721,.004947,
.000432,.004981,
.000141,.004997,
-.000149,.004997,
-.00044,.00498,
-.000729,.004946,
-.001015,.004895,
-.00129,.00483,
-.00044,.00398,
90.*
%
%ADD20MACRO20*%
%AMMACRO28*
4,1,15,-.00398,.00044,
-.003999,.000208,
-.004004,-.000025,
-.003996,-.000258,
-.00398,-.00044,
-.00483,-.00129,
-.004897,-.001007,
-.004947,-.000721,
-.004981,-.000432,
-.004997,-.000141,
-.004997,.000149,
-.00498,.00044,
-.004946,.000729,
-.004895,.001015,
-.00483,.00129,
-.00398,.00044,
90.*
4,1,15,-.00044,-.00398,
-.000208,-.003999,
.000025,-.004004,
.000258,-.003996,
.00044,-.00398,
.00129,-.00483,
.001007,-.004897,
.000721,-.004947,
.000432,-.004981,
.000141,-.004997,
-.000149,-.004997,
-.00044,-.00498,
-.000729,-.004946,
-.001015,-.004895,
-.00129,-.00483,
-.00044,-.00398,
90.*
4,1,15,.00398,-.00044,
.003999,-.000208,
.004004,.000025,
.003996,.000258,
.00398,.00044,
.00483,.00129,
.004897,.001007,
.004947,.000721,
.004981,.000432,
.004997,.000141,
.004997,-.000149,
.00498,-.00044,
.004946,-.000729,
.004895,-.001015,
.00483,-.00129,
.00398,-.00044,
90.*
4,1,15,.00044,.00398,
.000208,.003999,
-.000025,.004004,
-.000258,.003996,
-.00044,.00398,
-.00129,.00483,
-.001007,.004897,
-.000721,.004947,
-.000432,.004981,
-.000141,.004997,
.000149,.004997,
.00044,.00498,
.000729,.004946,
.001015,.004895,
.00129,.00483,
.00044,.00398,
90.*
%
%ADD28MACRO28*%
%AMMACRO11*
4,1,15,.00398,.00044,
.003999,.000208,
.004004,-.000025,
.003996,-.000258,
.00398,-.00044,
.00483,-.00129,
.004897,-.001007,
.004947,-.000721,
.004981,-.000432,
.004997,-.000141,
.004997,.000149,
.00498,.00044,
.004946,.000729,
.004895,.001015,
.00483,.00129,
.00398,.00044,
0.0*
4,1,15,.00044,-.00398,
.000208,-.003999,
-.000025,-.004004,
-.000258,-.003996,
-.00044,-.00398,
-.00129,-.00483,
-.001007,-.004897,
-.000721,-.004947,
-.000432,-.004981,
-.000141,-.004997,
.000149,-.004997,
.00044,-.00498,
.000729,-.004946,
.001015,-.004895,
.00129,-.00483,
.00044,-.00398,
0.0*
4,1,15,-.00398,-.00044,
-.003999,-.000208,
-.004004,.000025,
-.003996,.000258,
-.00398,.00044,
-.00483,.00129,
-.004897,.001007,
-.004947,.000721,
-.004981,.000432,
-.004997,.000141,
-.004997,-.000149,
-.00498,-.00044,
-.004946,-.000729,
-.004895,-.001015,
-.00483,-.00129,
-.00398,-.00044,
0.0*
4,1,15,-.00044,.00398,
-.000208,.003999,
.000025,.004004,
.000258,.003996,
.00044,.00398,
.00129,.00483,
.001007,.004897,
.000721,.004947,
.000432,.004981,
.000141,.004997,
-.000149,.004997,
-.00044,.00498,
-.000729,.004946,
-.001015,.004895,
-.00129,.00483,
-.00044,.00398,
0.0*
%
%ADD11MACRO11*%
%AMMACRO17*
4,1,13,.02442,.01028,
.025834,.005883,
.026463,.001308,
.026288,-.003307,
.025315,-.007822,
.02442,-.01028,
.02819,-.01405,
.030201,-.008941,
.031295,-.003561,
.031438,.001927,
.030626,.007357,
.028883,.012564,
.02819,.01405,
.02442,.01028,
180.*
4,1,13,.01028,-.02442,
.005883,-.025834,
.001308,-.026463,
-.003307,-.026288,
-.007822,-.025315,
-.01028,-.02442,
-.01405,-.02819,
-.008941,-.030201,
-.003561,-.031295,
.001927,-.031438,
.007357,-.030626,
.012564,-.028883,
.01405,-.02819,
.01028,-.02442,
180.*
4,1,13,-.02442,-.01028,
-.025834,-.005883,
-.026463,-.001308,
-.026288,.003307,
-.025315,.007822,
-.02442,.01028,
-.02819,.01405,
-.030201,.008941,
-.031295,.003561,
-.031438,-.001927,
-.030626,-.007357,
-.028883,-.012564,
-.02819,-.01405,
-.02442,-.01028,
180.*
4,1,13,-.01028,.02442,
-.005883,.025834,
-.001308,.026463,
.003307,.026288,
.007822,.025315,
.01028,.02442,
.01405,.02819,
.008941,.030201,
.003561,.031295,
-.001927,.031438,
-.007357,.030626,
-.012564,.028883,
-.01405,.02819,
-.01028,.02442,
180.*
%
%ADD17MACRO17*%
%AMMACRO14*
4,1,15,-.00398,.00044,
-.003999,.000208,
-.004004,-.000025,
-.003996,-.000258,
-.00398,-.00044,
-.00483,-.00129,
-.004897,-.001007,
-.004947,-.000721,
-.004981,-.000432,
-.004997,-.000141,
-.004997,.000149,
-.00498,.00044,
-.004946,.000729,
-.004895,.001015,
-.00483,.00129,
-.00398,.00044,
0.0*
4,1,15,-.00044,-.00398,
-.000208,-.003999,
.000025,-.004004,
.000258,-.003996,
.00044,-.00398,
.00129,-.00483,
.001007,-.004897,
.000721,-.004947,
.000432,-.004981,
.000141,-.004997,
-.000149,-.004997,
-.00044,-.00498,
-.000729,-.004946,
-.001015,-.004895,
-.00129,-.00483,
-.00044,-.00398,
0.0*
4,1,15,.00398,-.00044,
.003999,-.000208,
.004004,.000025,
.003996,.000258,
.00398,.00044,
.00483,.00129,
.004897,.001007,
.004947,.000721,
.004981,.000432,
.004997,.000141,
.004997,-.000149,
.00498,-.00044,
.004946,-.000729,
.004895,-.001015,
.00483,-.00129,
.00398,-.00044,
0.0*
4,1,15,.00044,.00398,
.000208,.003999,
-.000025,.004004,
-.000258,.003996,
-.00044,.00398,
-.00129,.00483,
-.001007,.004897,
-.000721,.004947,
-.000432,.004981,
-.000141,.004997,
.000149,.004997,
.00044,.00498,
.000729,.004946,
.001015,.004895,
.00129,.00483,
.00044,.00398,
0.0*
%
%ADD14MACRO14*%
%ADD29C,.111*%
%ADD10C,.114*%
%ADD34C,.432*%
%ADD22C,.18*%
%ADD32C,.127*%
%ADD31C,.154*%
%ADD30C,.147*%
%ADD38C,.166*%
%ADD24C,.139*%
%AMMACRO18*
4,1,15,.00398,.00044,
.003999,.000208,
.004004,-.000025,
.003996,-.000258,
.00398,-.00044,
.00483,-.00129,
.004897,-.001007,
.004947,-.000721,
.004981,-.000432,
.004997,-.000141,
.004997,.000149,
.00498,.00044,
.004946,.000729,
.004895,.001015,
.00483,.00129,
.00398,.00044,
270.*
4,1,15,.00044,-.00398,
.000208,-.003999,
-.000025,-.004004,
-.000258,-.003996,
-.00044,-.00398,
-.00129,-.00483,
-.001007,-.004897,
-.000721,-.004947,
-.000432,-.004981,
-.000141,-.004997,
.000149,-.004997,
.00044,-.00498,
.000729,-.004946,
.001015,-.004895,
.00129,-.00483,
.00044,-.00398,
270.*
4,1,15,-.00398,-.00044,
-.003999,-.000208,
-.004004,.000025,
-.003996,.000258,
-.00398,.00044,
-.00483,.00129,
-.004897,.001007,
-.004947,.000721,
-.004981,.000432,
-.004997,.000141,
-.004997,-.000149,
-.00498,-.00044,
-.004946,-.000729,
-.004895,-.001015,
-.00483,-.00129,
-.00398,-.00044,
270.*
4,1,15,-.00044,.00398,
-.000208,.003999,
.000025,.004004,
.000258,.003996,
.00044,.00398,
.00129,.00483,
.001007,.004897,
.000721,.004947,
.000432,.004981,
.000141,.004997,
-.000149,.004997,
-.00044,.00498,
-.000729,.004946,
-.001015,.004895,
-.00129,.00483,
-.00044,.00398,
270.*
%
%ADD18MACRO18*%
%AMMACRO13*
4,1,15,.00398,.00044,
.003999,.000208,
.004004,-.000025,
.003996,-.000258,
.00398,-.00044,
.00483,-.00129,
.004897,-.001007,
.004947,-.000721,
.004981,-.000432,
.004997,-.000141,
.004997,.000149,
.00498,.00044,
.004946,.000729,
.004895,.001015,
.00483,.00129,
.00398,.00044,
180.*
4,1,15,.00044,-.00398,
.000208,-.003999,
-.000025,-.004004,
-.000258,-.003996,
-.00044,-.00398,
-.00129,-.00483,
-.001007,-.004897,
-.000721,-.004947,
-.000432,-.004981,
-.000141,-.004997,
.000149,-.004997,
.00044,-.00498,
.000729,-.004946,
.001015,-.004895,
.00129,-.00483,
.00044,-.00398,
180.*
4,1,15,-.00398,-.00044,
-.003999,-.000208,
-.004004,.000025,
-.003996,.000258,
-.00398,.00044,
-.00483,.00129,
-.004897,.001007,
-.004947,.000721,
-.004981,.000432,
-.004997,.000141,
-.004997,-.000149,
-.00498,-.00044,
-.004946,-.000729,
-.004895,-.001015,
-.00483,-.00129,
-.00398,-.00044,
180.*
4,1,15,-.00044,.00398,
-.000208,.003999,
.000025,.004004,
.000258,.003996,
.00044,.00398,
.00129,.00483,
.001007,.004897,
.000721,.004947,
.000432,.004981,
.000141,.004997,
-.000149,.004997,
-.00044,.00498,
-.000729,.004946,
-.001015,.004895,
-.00129,.00483,
-.00044,.00398,
180.*
%
%ADD13MACRO13*%
%AMMACRO27*
4,1,15,-.00398,.00044,
-.003999,.000208,
-.004004,-.000025,
-.003996,-.000258,
-.00398,-.00044,
-.00483,-.00129,
-.004897,-.001007,
-.004947,-.000721,
-.004981,-.000432,
-.004997,-.000141,
-.004997,.000149,
-.00498,.00044,
-.004946,.000729,
-.004895,.001015,
-.00483,.00129,
-.00398,.00044,
270.*
4,1,15,-.00044,-.00398,
-.000208,-.003999,
.000025,-.004004,
.000258,-.003996,
.00044,-.00398,
.00129,-.00483,
.001007,-.004897,
.000721,-.004947,
.000432,-.004981,
.000141,-.004997,
-.000149,-.004997,
-.00044,-.00498,
-.000729,-.004946,
-.001015,-.004895,
-.00129,-.00483,
-.00044,-.00398,
270.*
4,1,15,.00398,-.00044,
.003999,-.000208,
.004004,.000025,
.003996,.000258,
.00398,.00044,
.00483,.00129,
.004897,.001007,
.004947,.000721,
.004981,.000432,
.004997,.000141,
.004997,-.000149,
.00498,-.00044,
.004946,-.000729,
.004895,-.001015,
.00483,-.00129,
.00398,-.00044,
270.*
4,1,15,.00044,.00398,
.000208,.003999,
-.000025,.004004,
-.000258,.003996,
-.00044,.00398,
-.00129,.00483,
-.001007,.004897,
-.000721,.004947,
-.000432,.004981,
-.000141,.004997,
.000149,.004997,
.00044,.00498,
.000729,.004946,
.001015,.004895,
.00129,.00483,
.00044,.00398,
270.*
%
%ADD27MACRO27*%
%AMMACRO26*
4,1,15,-.00398,.00044,
-.003999,.000208,
-.004004,-.000025,
-.003996,-.000258,
-.00398,-.00044,
-.00483,-.00129,
-.004897,-.001007,
-.004947,-.000721,
-.004981,-.000432,
-.004997,-.000141,
-.004997,.000149,
-.00498,.00044,
-.004946,.000729,
-.004895,.001015,
-.00483,.00129,
-.00398,.00044,
180.*
4,1,15,-.00044,-.00398,
-.000208,-.003999,
.000025,-.004004,
.000258,-.003996,
.00044,-.00398,
.00129,-.00483,
.001007,-.004897,
.000721,-.004947,
.000432,-.004981,
.000141,-.004997,
-.000149,-.004997,
-.00044,-.00498,
-.000729,-.004946,
-.001015,-.004895,
-.00129,-.00483,
-.00044,-.00398,
180.*
4,1,15,.00398,-.00044,
.003999,-.000208,
.004004,.000025,
.003996,.000258,
.00398,.00044,
.00483,.00129,
.004897,.001007,
.004947,.000721,
.004981,.000432,
.004997,.000141,
.004997,-.000149,
.00498,-.00044,
.004946,-.000729,
.004895,-.001015,
.00483,-.00129,
.00398,-.00044,
180.*
4,1,15,.00044,.00398,
.000208,.003999,
-.000025,.004004,
-.000258,.003996,
-.00044,.00398,
-.00129,.00483,
-.001007,.004897,
-.000721,.004947,
-.000432,.004981,
-.000141,.004997,
.000149,.004997,
.00044,.00498,
.000729,.004946,
.001015,.004895,
.00129,.00483,
.00044,.00398,
180.*
%
%ADD26MACRO26*%
%ADD39C,.02*%
%ADD40C,.006*%
%ADD56O,.10334X.04822*%
%ADD44C,.06104*%
%ADD43R,.09302X.12602*%
%ADD48R,.09304X.12602*%
%ADD42C,.07704*%
%ADD51O,.515X.315*%
%ADD41C,.11004*%
%ADD47C,.14304*%
%ADD45C,.13504*%
%ADD46C,.37504*%
%ADD49C,.29531*%
%ADD52O,.55202X.78802*%
%ADD53O,.09834X.04322*%
%ADD50O,.55204X.78804*%
%ADD55O,.09854X.04342*%
%ADD54O,.09836X.04324*%
G75*
%LPD*%
G75*
G36*
G01X-6000Y-6000D02*
X1940843D01*
Y1525685D01*
X-6000D01*
Y-6000D01*
G37*
%LPC*%
G75*
G36*
G01X14815Y1515748D02*
G02X15748Y1516681I933J0D01*
G01X60039D01*
G02X60972Y1515748I0J-933D01*
G01Y1509055D01*
G03X67913Y1502114I6941J0D01*
G01X93504D01*
G03X100445Y1509055I0J6941D01*
G01Y1515748D01*
G02X101378Y1516681I933J0D01*
G01X280709D01*
G02X281642Y1515748I0J-933D01*
G01Y1500000D01*
G03X288583Y1493059I6941J0D01*
G01X493307D01*
G03X500248Y1500000I0J6941D01*
G01Y1515748D01*
G02X501181Y1516681I933J0D01*
G01X680512D01*
G02X681445Y1515748I0J-933D01*
G01Y1509055D01*
G03X688386Y1502114I6941J0D01*
G01X713976D01*
G03X720917Y1509055I0J6941D01*
G01Y1515748D01*
G02X721850Y1516681I933J0D01*
G01X775591D01*
G02X776524Y1515748I0J-933D01*
G01Y1500000D01*
G03X783465Y1493059I6941J0D01*
G01X988189D01*
G03X995130Y1500000I0J6941D01*
G01Y1515748D01*
G02X996063Y1516681I933J0D01*
G01X1059198D01*
G02X1059856Y1516408I-1J-933D01*
G01X1069361Y1506903D01*
G02X1069634Y1506245I-660J-660D01*
G01Y1421260D01*
G03X1076575Y1414319I6941J0D01*
G01X1085630D01*
G03X1092571Y1421260I0J6941D01*
G01Y1506245D01*
G02X1092844Y1506903I933J-1D01*
G01X1102349Y1516408D01*
G02X1103007Y1516681I659J-660D01*
G01X1207283D01*
G02X1208216Y1515748I0J-933D01*
G01Y1509055D01*
G03X1215157Y1502114I6941J0D01*
G01X1240748D01*
G03X1247689Y1509055I0J6941D01*
G01Y1515748D01*
G02X1248622Y1516681I933J0D01*
G01X1427953D01*
G02X1428886Y1515748I0J-933D01*
G01Y1500000D01*
G03X1435827Y1493059I6941J0D01*
G01X1640551D01*
G03X1647492Y1500000I0J6941D01*
G01Y1515748D01*
G02X1648425Y1516681I933J0D01*
G01X1827756D01*
G02X1828689Y1515748I0J-933D01*
G01Y1509055D01*
G03X1835630Y1502114I6941J0D01*
G01X1861220D01*
G03X1868161Y1509055I0J6941D01*
G01Y1515748D01*
G02X1869094Y1516681I933J0D01*
G01X1919094D01*
G02X1920027Y1515748I0J-933D01*
G01Y1464567D01*
G03X1926967Y1457626I6941J0D01*
G01X1930906D01*
G02X1931839Y1456693I0J-933D01*
G01Y3937D01*
G02X1930906Y3004I-933J0D01*
G01X1228346D01*
G02X1227413Y3937I0J933D01*
G01Y185827D01*
G03X1220472Y192768I-6941J0D01*
G01X1062992D01*
G02X1062059Y193701I0J933D01*
G01Y244094D01*
G03X1055118Y251035I-6941J0D01*
G01X818897D01*
G03X811957Y244095I1J-6941D01*
G01Y193701D01*
G02X811024Y192768I-933J0D01*
G01X787402D01*
G03X780461Y185827I0J-6941D01*
G01Y3937D01*
G02X779528Y3004I-933J0D01*
G01X3937D01*
G02X3004Y3937I0J933D01*
G01Y1456693D01*
G02X3937Y1457626I933J0D01*
G01X7874D01*
G03X14815Y1464567I0J6941D01*
G01Y1515748D01*
G37*
%LPD*%
G75*
G36*
G01X1729037Y262991D02*
G02I-55120J0D01*
G37*
G36*
G01X558368Y715747D02*
G02I-55121J0D01*
G37*
G36*
G01X1575626Y103397D02*
G02X1608421Y103767I16499J-8808D01*
G02X1575626Y103397I-16295J-9279D01*
G37*
G36*
G01X126209Y59318D02*
G02X126008Y59519I0J201D01*
G01Y60319D01*
G02X126209Y60520I201J0D01*
G01X129409D01*
G02X129610Y60319I0J-201D01*
G01Y59519D01*
G02X129409Y59318I-201J0D01*
G01X126209D01*
G37*
G36*
G01Y57118D02*
G02X126008Y57319I0J201D01*
G01Y58119D01*
G02X126209Y58320I201J0D01*
G01X129409D01*
G02X129610Y58119I0J-201D01*
G01Y57319D01*
G02X129409Y57118I-201J0D01*
G01X126209D01*
G37*
G36*
G01X126076Y76319D02*
G02X129900I1912J0D01*
G01Y71318D01*
G02X126076Y71319I-1912J1D01*
G01Y76319D01*
G37*
G36*
G01X133072Y61269D02*
G02X136894I1911J0D01*
G01Y56768D01*
G02X133072Y56769I-1911J1D01*
G01Y61269D01*
G37*
G36*
G01X126209Y512074D02*
G02X126008Y512275I0J201D01*
G01Y513075D01*
G02X126209Y513276I201J0D01*
G01X129409D01*
G02X129610Y513075I0J-201D01*
G01Y512275D01*
G02X129409Y512074I-201J0D01*
G01X126209D01*
G37*
G36*
G01Y509874D02*
G02X126008Y510075I0J201D01*
G01Y510875D01*
G02X126209Y511076I201J0D01*
G01X129409D01*
G02X129610Y510875I0J-201D01*
G01Y510075D01*
G02X129409Y509874I-201J0D01*
G01X126209D01*
G37*
G36*
G01X129900Y524075D02*
G02X126076I-1912J0D01*
G01Y529076D01*
G02X129900Y529075I1912J-1D01*
G01Y524075D01*
G37*
G36*
G01X133072Y514025D02*
G02X136894I1911J0D01*
G01Y509524D01*
G02X133072Y509525I-1911J1D01*
G01Y514025D01*
G37*
G36*
G01X126209Y964830D02*
G02X126008Y965031I0J201D01*
G01Y965831D01*
G02X126209Y966032I201J0D01*
G01X129409D01*
G02X129610Y965831I0J-201D01*
G01Y965031D01*
G02X129409Y964830I-201J0D01*
G01X126209D01*
G37*
G36*
G01Y962630D02*
G02X126008Y962831I0J201D01*
G01Y963631D01*
G02X126209Y963832I201J0D01*
G01X129409D01*
G02X129610Y963631I0J-201D01*
G01Y962831D01*
G02X129409Y962630I-201J0D01*
G01X126209D01*
G37*
G36*
G01X126076Y981831D02*
G02X129900I1912J0D01*
G01Y976830D01*
G02X126076Y976831I-1912J1D01*
G01Y981831D01*
G37*
G36*
G01X136894Y962281D02*
G02X133072I-1911J0D01*
G01Y966782D01*
G02X136894Y966781I1911J-1D01*
G01Y962281D01*
G37*
G36*
G01X250421Y59318D02*
G02X250220Y59519I0J201D01*
G01Y60319D01*
G02X250421Y60520I201J0D01*
G01X253621D01*
G02X253822Y60319I0J-201D01*
G01Y59519D01*
G02X253621Y59318I-201J0D01*
G01X250421D01*
G37*
G36*
G01Y57118D02*
G02X250220Y57319I0J201D01*
G01Y58119D01*
G02X250421Y58320I201J0D01*
G01X253621D01*
G02X253822Y58119I0J-201D01*
G01Y57319D01*
G02X253621Y57118I-201J0D01*
G01X250421D01*
G37*
G36*
G01X250288Y76319D02*
G02X254112I1912J0D01*
G01Y71318D01*
G02X250288Y71319I-1912J1D01*
G01Y76319D01*
G37*
G36*
G01X257284Y61269D02*
G02X261106I1911J0D01*
G01Y56768D01*
G02X257284Y56769I-1911J1D01*
G01Y61269D01*
G37*
G36*
G01X250421Y512074D02*
G02X250220Y512275I0J201D01*
G01Y513075D01*
G02X250421Y513276I201J0D01*
G01X253621D01*
G02X253822Y513075I0J-201D01*
G01Y512275D01*
G02X253621Y512074I-201J0D01*
G01X250421D01*
G37*
G36*
G01Y509874D02*
G02X250220Y510075I0J201D01*
G01Y510875D01*
G02X250421Y511076I201J0D01*
G01X253621D01*
G02X253822Y510875I0J-201D01*
G01Y510075D01*
G02X253621Y509874I-201J0D01*
G01X250421D01*
G37*
G36*
G01X254112Y524075D02*
G02X250288I-1912J0D01*
G01Y529076D01*
G02X254112Y529075I1912J-1D01*
G01Y524075D01*
G37*
G36*
G01X257284Y514025D02*
G02X261106I1911J0D01*
G01Y509524D01*
G02X257284Y509525I-1911J1D01*
G01Y514025D01*
G37*
G36*
G01X250421Y964830D02*
G02X250220Y965031I0J201D01*
G01Y965831D01*
G02X250421Y966032I201J0D01*
G01X253621D01*
G02X253822Y965831I0J-201D01*
G01Y965031D01*
G02X253621Y964830I-201J0D01*
G01X250421D01*
G37*
G36*
G01Y962630D02*
G02X250220Y962831I0J201D01*
G01Y963631D01*
G02X250421Y963832I201J0D01*
G01X253621D01*
G02X253822Y963631I0J-201D01*
G01Y962831D01*
G02X253621Y962630I-201J0D01*
G01X250421D01*
G37*
G36*
G01X261106Y962281D02*
G02X257284I-1911J0D01*
G01Y966782D01*
G02X261106Y966781I1911J-1D01*
G01Y962281D01*
G37*
G36*
G01X250288Y981831D02*
G02X254112I1912J0D01*
G01Y976830D01*
G02X250288Y976831I-1912J1D01*
G01Y981831D01*
G37*
G36*
G01X374634Y59318D02*
G02X374432Y59519I-1J201D01*
G01Y60319D01*
G02X374634Y60520I202J-1D01*
G01X377834D01*
G02X378036Y60319I1J-201D01*
G01Y59519D01*
G02X377834Y59318I-202J1D01*
G01X374634D01*
G37*
G36*
G01Y57118D02*
G02X374432Y57319I-1J201D01*
G01Y58119D01*
G02X374634Y58320I202J-1D01*
G01X377834D01*
G02X378036Y58119I1J-201D01*
G01Y57319D01*
G02X377834Y57118I-202J1D01*
G01X374634D01*
G37*
G36*
G01X381496Y61269D02*
G02X385320I1912J0D01*
G01Y56768D01*
G02X381496Y56769I-1912J1D01*
G01Y61269D01*
G37*
G36*
G01X374502Y76319D02*
G02X378324I1911J0D01*
G01Y71318D01*
G02X374502Y71319I-1911J1D01*
G01Y76319D01*
G37*
G36*
G01X374634Y512074D02*
G02X374432Y512275I-1J201D01*
G01Y513075D01*
G02X374634Y513276I202J-1D01*
G01X377834D01*
G02X378036Y513075I1J-201D01*
G01Y512275D01*
G02X377834Y512074I-202J1D01*
G01X374634D01*
G37*
G36*
G01Y509874D02*
G02X374432Y510075I-1J201D01*
G01Y510875D01*
G02X374634Y511076I202J-1D01*
G01X377834D01*
G02X378036Y510875I1J-201D01*
G01Y510075D01*
G02X377834Y509874I-202J1D01*
G01X374634D01*
G37*
G36*
G01X378324Y524075D02*
G02X374502I-1911J0D01*
G01Y529076D01*
G02X378324Y529075I1911J-1D01*
G01Y524075D01*
G37*
G36*
G01X381496Y514025D02*
G02X385320I1912J0D01*
G01Y509524D01*
G02X381496Y509525I-1912J1D01*
G01Y514025D01*
G37*
G36*
G01X374634Y964830D02*
G02X374432Y965031I-1J201D01*
G01Y965831D01*
G02X374634Y966032I202J-1D01*
G01X377834D01*
G02X378036Y965831I1J-201D01*
G01Y965031D01*
G02X377834Y964830I-202J1D01*
G01X374634D01*
G37*
G36*
G01Y962630D02*
G02X374432Y962831I-1J201D01*
G01Y963631D01*
G02X374634Y963832I202J-1D01*
G01X377834D01*
G02X378036Y963631I1J-201D01*
G01Y962831D01*
G02X377834Y962630I-202J1D01*
G01X374634D01*
G37*
G36*
G01X374502Y981831D02*
G02X378324I1911J0D01*
G01Y976830D01*
G02X374502Y976831I-1911J1D01*
G01Y981831D01*
G37*
G36*
G01X385320Y962281D02*
G02X381496I-1912J0D01*
G01Y966782D01*
G02X385320Y966781I1912J-1D01*
G01Y962281D01*
G37*
G36*
G01X623752Y1291748D02*
Y1287154D01*
X620846Y1284248D01*
X598154D01*
X593748Y1288654D01*
Y1300722D01*
X408680D01*
X401248Y1308154D01*
Y1364346D01*
X404748Y1367846D01*
Y1435479D01*
X408276Y1439006D01*
X431624D01*
X443109Y1427522D01*
X485893D01*
X499163Y1414252D01*
X636252D01*
Y1291748D01*
X623752D01*
G37*
G36*
G01X498846Y59318D02*
G02X498644Y59519I-1J201D01*
G01Y60319D01*
G02X498846Y60520I202J-1D01*
G01X502046D01*
G02X502248Y60319I1J-201D01*
G01Y59519D01*
G02X502046Y59318I-202J1D01*
G01X498846D01*
G37*
G36*
G01Y57118D02*
G02X498644Y57319I-1J201D01*
G01Y58119D01*
G02X498846Y58320I202J-1D01*
G01X502046D01*
G02X502248Y58119I1J-201D01*
G01Y57319D01*
G02X502046Y57118I-202J1D01*
G01X498846D01*
G37*
G36*
G01X498714Y76319D02*
G02X502536I1911J0D01*
G01Y71318D01*
G02X498714Y71319I-1911J1D01*
G01Y76319D01*
G37*
G36*
G01X505708Y61269D02*
G02X509532I1912J0D01*
G01Y56768D01*
G02X505708Y56769I-1912J1D01*
G01Y61269D01*
G37*
G36*
G01X498846Y512074D02*
G02X498644Y512275I-1J201D01*
G01Y513075D01*
G02X498846Y513276I202J-1D01*
G01X502046D01*
G02X502248Y513075I1J-201D01*
G01Y512275D01*
G02X502046Y512074I-202J1D01*
G01X498846D01*
G37*
G36*
G01Y509874D02*
G02X498644Y510075I-1J201D01*
G01Y510875D01*
G02X498846Y511076I202J-1D01*
G01X502046D01*
G02X502248Y510875I1J-201D01*
G01Y510075D01*
G02X502046Y509874I-202J1D01*
G01X498846D01*
G37*
G36*
G01X502536Y524075D02*
G02X498714I-1911J0D01*
G01Y529076D01*
G02X502536Y529075I1911J-1D01*
G01Y524075D01*
G37*
G36*
G01X505708Y514025D02*
G02X509532I1912J0D01*
G01Y509524D01*
G02X505708Y509525I-1912J1D01*
G01Y514025D01*
G37*
G36*
G01X498846Y964830D02*
G02X498644Y965031I-1J201D01*
G01Y965831D01*
G02X498846Y966032I202J-1D01*
G01X502046D01*
G02X502248Y965831I1J-201D01*
G01Y965031D01*
G02X502046Y964830I-202J1D01*
G01X498846D01*
G37*
G36*
G01Y962630D02*
G02X498644Y962831I-1J201D01*
G01Y963631D01*
G02X498846Y963832I202J-1D01*
G01X502046D01*
G02X502248Y963631I1J-201D01*
G01Y962831D01*
G02X502046Y962630I-202J1D01*
G01X498846D01*
G37*
G36*
G01X498714Y981831D02*
G02X502536I1911J0D01*
G01Y976830D01*
G02X498714Y976831I-1911J1D01*
G01Y981831D01*
G37*
G36*
G01X509532Y962281D02*
G02X505708I-1912J0D01*
G01Y966782D01*
G02X509532Y966781I1912J-1D01*
G01Y962281D01*
G37*
G36*
G01X623059Y59318D02*
G02X622858Y59519I0J201D01*
G01Y60319D01*
G02X623059Y60520I201J0D01*
G01X626259D01*
G02X626460Y60319I0J-201D01*
G01Y59519D01*
G02X626259Y59318I-201J0D01*
G01X623059D01*
G37*
G36*
G01Y57118D02*
G02X622858Y57319I0J201D01*
G01Y58119D01*
G02X623059Y58320I201J0D01*
G01X626259D01*
G02X626460Y58119I0J-201D01*
G01Y57319D01*
G02X626259Y57118I-201J0D01*
G01X623059D01*
G37*
G36*
G01X622926Y76319D02*
G02X626750I1912J0D01*
G01Y71318D01*
G02X622926Y71319I-1912J1D01*
G01Y76319D01*
G37*
G36*
G01X629922Y61269D02*
G02X633744I1911J0D01*
G01Y56768D01*
G02X629922Y56769I-1911J1D01*
G01Y61269D01*
G37*
G36*
G01X623059Y512074D02*
G02X622858Y512275I0J201D01*
G01Y513075D01*
G02X623059Y513276I201J0D01*
G01X626259D01*
G02X626460Y513075I0J-201D01*
G01Y512275D01*
G02X626259Y512074I-201J0D01*
G01X623059D01*
G37*
G36*
G01Y509874D02*
G02X622858Y510075I0J201D01*
G01Y510875D01*
G02X623059Y511076I201J0D01*
G01X626259D01*
G02X626460Y510875I0J-201D01*
G01Y510075D01*
G02X626259Y509874I-201J0D01*
G01X623059D01*
G37*
G36*
G01X626750Y524075D02*
G02X622926I-1912J0D01*
G01Y529076D01*
G02X626750Y529075I1912J-1D01*
G01Y524075D01*
G37*
G36*
G01X629922Y514025D02*
G02X633744I1911J0D01*
G01Y509524D01*
G02X629922Y509525I-1911J1D01*
G01Y514025D01*
G37*
G36*
G01X623059Y964830D02*
G02X622858Y965031I0J201D01*
G01Y965831D01*
G02X623059Y966032I201J0D01*
G01X626259D01*
G02X626460Y965831I0J-201D01*
G01Y965031D01*
G02X626259Y964830I-201J0D01*
G01X623059D01*
G37*
G36*
G01Y962630D02*
G02X622858Y962831I0J201D01*
G01Y963631D01*
G02X623059Y963832I201J0D01*
G01X626259D01*
G02X626460Y963631I0J-201D01*
G01Y962831D01*
G02X626259Y962630I-201J0D01*
G01X623059D01*
G37*
G36*
G01X626750Y976831D02*
G02X622926I-1912J0D01*
G01Y981832D01*
G02X626750Y981831I1912J-1D01*
G01Y976831D01*
G37*
G36*
G01X633744Y962281D02*
G02X629922I-1911J0D01*
G01Y966782D01*
G02X633744Y966781I1911J-1D01*
G01Y962281D01*
G37*
G36*
G01X808902Y1410596D02*
Y1295254D01*
X805396Y1291748D01*
X651098D01*
Y1414252D01*
X805246D01*
X808902Y1410596D01*
G37*
G36*
G01X747272Y59318D02*
G02X747070Y59519I-1J201D01*
G01Y60319D01*
G02X747272Y60520I202J-1D01*
G01X750472D01*
G02X750674Y60319I1J-201D01*
G01Y59519D01*
G02X750472Y59318I-202J1D01*
G01X747272D01*
G37*
G36*
G01Y57118D02*
G02X747070Y57319I-1J201D01*
G01Y58119D01*
G02X747272Y58320I202J-1D01*
G01X750472D01*
G02X750674Y58119I1J-201D01*
G01Y57319D01*
G02X750472Y57118I-202J1D01*
G01X747272D01*
G37*
G36*
G01X754134Y61269D02*
G02X757958I1912J0D01*
G01Y56768D01*
G02X754134Y56769I-1912J1D01*
G01Y61269D01*
G37*
G36*
G01X747140Y76319D02*
G02X750962I1911J0D01*
G01Y71318D01*
G02X747140Y71319I-1911J1D01*
G01Y76319D01*
G37*
G36*
G01X747272Y512074D02*
G02X747070Y512275I-1J201D01*
G01Y513075D01*
G02X747272Y513276I202J-1D01*
G01X750472D01*
G02X750674Y513075I1J-201D01*
G01Y512275D01*
G02X750472Y512074I-202J1D01*
G01X747272D01*
G37*
G36*
G01Y509874D02*
G02X747070Y510075I-1J201D01*
G01Y510875D01*
G02X747272Y511076I202J-1D01*
G01X750472D01*
G02X750674Y510875I1J-201D01*
G01Y510075D01*
G02X750472Y509874I-202J1D01*
G01X747272D01*
G37*
G36*
G01X754134Y514025D02*
G02X757958I1912J0D01*
G01Y509524D01*
G02X754134Y509525I-1912J1D01*
G01Y514025D01*
G37*
G36*
G01X747140Y529075D02*
G02X750962I1911J0D01*
G01Y524074D01*
G02X747140Y524075I-1911J1D01*
G01Y529075D01*
G37*
G36*
G01X747272Y964830D02*
G02X747070Y965031I-1J201D01*
G01Y965831D01*
G02X747272Y966032I202J-1D01*
G01X750472D01*
G02X750674Y965831I1J-201D01*
G01Y965031D01*
G02X750472Y964830I-202J1D01*
G01X747272D01*
G37*
G36*
G01Y962630D02*
G02X747070Y962831I-1J201D01*
G01Y963631D01*
G02X747272Y963832I202J-1D01*
G01X750472D01*
G02X750674Y963631I1J-201D01*
G01Y962831D01*
G02X750472Y962630I-202J1D01*
G01X747272D01*
G37*
G36*
G01X747140Y981831D02*
G02X750962I1911J0D01*
G01Y976830D01*
G02X747140Y976831I-1911J1D01*
G01Y981831D01*
G37*
G36*
G01X757958Y962281D02*
G02X754134I-1912J0D01*
G01Y966782D01*
G02X757958Y966781I1912J-1D01*
G01Y962281D01*
G37*
G36*
G01X828934Y277165D02*
G02X824610I-2162J0D01*
G01Y282678D01*
G02X828934Y282677I2162J-1D01*
G01Y277165D01*
G37*
G36*
G01X857280D02*
G02X852956I-2162J0D01*
G01Y282678D01*
G02X857280Y282677I2162J-1D01*
G01Y277165D01*
G37*
G36*
G01X843106D02*
G02X838784I-2161J0D01*
G01Y282678D01*
G02X843106Y282677I2161J-1D01*
G01Y277165D01*
G37*
G36*
G01X864366Y258268D02*
G02X860044I-2161J0D01*
G01Y263780D01*
G02X864366Y263779I2161J-1D01*
G01Y258268D01*
G37*
G36*
G01X850194D02*
G02X845870I-2162J0D01*
G01Y263780D01*
G02X850194Y263779I2162J-1D01*
G01Y258268D01*
G37*
G36*
G01X836020D02*
G02X831698I-2161J0D01*
G01Y263780D01*
G02X836020Y263779I2161J-1D01*
G01Y258268D01*
G37*
G36*
G01X864366Y300787D02*
G02X860044I-2161J0D01*
G01Y306300D01*
G02X864366Y306299I2161J-1D01*
G01Y300787D01*
G37*
G36*
G01X850194D02*
G02X845870I-2162J0D01*
G01Y306300D01*
G02X850194Y306299I2162J-1D01*
G01Y300787D01*
G37*
G36*
G01X852956Y311023D02*
G02X857280I2162J0D01*
G01Y305511D01*
G02X852956Y305512I-2162J1D01*
G01Y311023D01*
G37*
G36*
G01X838784D02*
G02X843106I2161J0D01*
G01Y305511D01*
G02X838784Y305512I-2161J1D01*
G01Y311023D01*
G37*
G36*
G01X836020Y300787D02*
G02X831698I-2161J0D01*
G01Y306300D01*
G02X836020Y306299I2161J-1D01*
G01Y300787D01*
G37*
G36*
G01X824610Y311023D02*
G02X828934I2162J0D01*
G01Y305511D01*
G02X824610Y305512I-2162J1D01*
G01Y311023D01*
G37*
G36*
G01X828934Y291338D02*
G02X824610I-2162J0D01*
G01Y296851D01*
G02X828934Y296850I2162J-1D01*
G01Y291338D01*
G37*
G36*
G01X871454Y277165D02*
G02X867130I-2162J0D01*
G01Y282678D01*
G02X871454Y282677I2162J-1D01*
G01Y277165D01*
G37*
G36*
G01X874216Y263779D02*
G02X878540I2162J0D01*
G01Y258267D01*
G02X874216Y258268I-2162J1D01*
G01Y263779D01*
G37*
G36*
G01X878540Y300787D02*
G02X874216I-2162J0D01*
G01Y306300D01*
G02X878540Y306299I2162J-1D01*
G01Y300787D01*
G37*
G36*
G01X867130Y311023D02*
G02X871454I2162J0D01*
G01Y305511D01*
G02X867130Y305512I-2162J1D01*
G01Y311023D01*
G37*
G36*
G01X1264678Y59318D02*
G02X1264476Y59519I-1J201D01*
G01Y60319D01*
G02X1264678Y60520I202J-1D01*
G01X1267878D01*
G02X1268080Y60319I1J-201D01*
G01Y59519D01*
G02X1267878Y59318I-202J1D01*
G01X1264678D01*
G37*
G36*
G01Y57118D02*
G02X1264476Y57319I-1J201D01*
G01Y58119D01*
G02X1264678Y58320I202J-1D01*
G01X1267878D01*
G02X1268080Y58119I1J-201D01*
G01Y57319D01*
G02X1267878Y57118I-202J1D01*
G01X1264678D01*
G37*
G36*
G01X1270400Y66738D02*
G02Y70562I0J1912D01*
G01X1275401D01*
G02X1275400Y66738I-1J-1912D01*
G01X1270400D01*
G37*
G36*
G01X1261250Y55562D02*
G02Y51738I0J-1912D01*
G01X1256749D01*
G02X1256750Y55562I1J1912D01*
G01X1261250D01*
G37*
G36*
G01X1264678Y512074D02*
G02X1264476Y512275I-1J201D01*
G01Y513075D01*
G02X1264678Y513276I202J-1D01*
G01X1267878D01*
G02X1268080Y513075I1J-201D01*
G01Y512275D01*
G02X1267878Y512074I-202J1D01*
G01X1264678D01*
G37*
G36*
G01Y509874D02*
G02X1264476Y510075I-1J201D01*
G01Y510875D01*
G02X1264678Y511076I202J-1D01*
G01X1267878D01*
G02X1268080Y510875I1J-201D01*
G01Y510075D01*
G02X1267878Y509874I-202J1D01*
G01X1264678D01*
G37*
G36*
G01X1261250Y508318D02*
G02Y504494I0J-1912D01*
G01X1256749D01*
G02X1256750Y508318I1J1912D01*
G01X1261250D01*
G37*
G36*
G01X1270400Y519494D02*
G02Y523318I0J1912D01*
G01X1275401D01*
G02X1275400Y519494I-1J-1912D01*
G01X1270400D01*
G37*
G36*
G01X1264678Y964830D02*
G02X1264476Y965031I-1J201D01*
G01Y965831D01*
G02X1264678Y966032I202J-1D01*
G01X1267878D01*
G02X1268080Y965831I1J-201D01*
G01Y965031D01*
G02X1267878Y964830I-202J1D01*
G01X1264678D01*
G37*
G36*
G01Y962630D02*
G02X1264476Y962831I-1J201D01*
G01Y963631D01*
G02X1264678Y963832I202J-1D01*
G01X1267878D01*
G02X1268080Y963631I1J-201D01*
G01Y962831D01*
G02X1267878Y962630I-202J1D01*
G01X1264678D01*
G37*
G36*
G01X1272064Y981831D02*
G02X1275886I1911J0D01*
G01Y976830D01*
G02X1272064Y976831I-1911J1D01*
G01Y981831D01*
G37*
G36*
G01X1259402Y961861D02*
G02X1255578I-1912J0D01*
G01Y966362D01*
G02X1259402Y966361I1912J-1D01*
G01Y961861D01*
G37*
G36*
G01X1388891Y59318D02*
G02X1388690Y59519I0J201D01*
G01Y60319D01*
G02X1388891Y60520I201J0D01*
G01X1392091D01*
G02X1392292Y60319I0J-201D01*
G01Y59519D01*
G02X1392091Y59318I-201J0D01*
G01X1388891D01*
G37*
G36*
G01Y57118D02*
G02X1388690Y57319I0J201D01*
G01Y58119D01*
G02X1388891Y58320I201J0D01*
G01X1392091D01*
G02X1392292Y58119I0J-201D01*
G01Y57319D01*
G02X1392091Y57118I-201J0D01*
G01X1388891D01*
G37*
G36*
G01X1399613Y70562D02*
G02Y66738I0J-1912D01*
G01X1394612D01*
G02X1394613Y70562I1J1912D01*
G01X1399613D01*
G37*
G36*
G01X1385463Y55562D02*
G02Y51738I0J-1912D01*
G01X1380962D01*
G02X1380963Y55562I1J1912D01*
G01X1385463D01*
G37*
G36*
G01X1388891Y512074D02*
G02X1388690Y512275I0J201D01*
G01Y513075D01*
G02X1388891Y513276I201J0D01*
G01X1392091D01*
G02X1392292Y513075I0J-201D01*
G01Y512275D01*
G02X1392091Y512074I-201J0D01*
G01X1388891D01*
G37*
G36*
G01Y509874D02*
G02X1388690Y510075I0J201D01*
G01Y510875D01*
G02X1388891Y511076I201J0D01*
G01X1392091D01*
G02X1392292Y510875I0J-201D01*
G01Y510075D01*
G02X1392091Y509874I-201J0D01*
G01X1388891D01*
G37*
G36*
G01X1399613Y523318D02*
G02Y519494I0J-1912D01*
G01X1394612D01*
G02X1394613Y523318I1J1912D01*
G01X1399613D01*
G37*
G36*
G01X1385463Y508318D02*
G02Y504494I0J-1912D01*
G01X1380962D01*
G02X1380963Y508318I1J1912D01*
G01X1385463D01*
G37*
G36*
G01X1388891Y964830D02*
G02X1388690Y965031I0J201D01*
G01Y965831D01*
G02X1388891Y966032I201J0D01*
G01X1392091D01*
G02X1392292Y965831I0J-201D01*
G01Y965031D01*
G02X1392091Y964830I-201J0D01*
G01X1388891D01*
G37*
G36*
G01Y962630D02*
G02X1388690Y962831I0J201D01*
G01Y963631D01*
G02X1388891Y963832I201J0D01*
G01X1392091D01*
G02X1392292Y963631I0J-201D01*
G01Y962831D01*
G02X1392091Y962630I-201J0D01*
G01X1388891D01*
G37*
G36*
G01X1396276Y981831D02*
G02X1400100I1912J0D01*
G01Y976830D01*
G02X1396276Y976831I-1912J1D01*
G01Y981831D01*
G37*
G36*
G01X1383574Y961881D02*
G02X1379752I-1911J0D01*
G01Y966382D01*
G02X1383574Y966381I1911J-1D01*
G01Y961881D01*
G37*
G36*
G01X1513103Y59318D02*
G02X1512902Y59519I0J201D01*
G01Y60319D01*
G02X1513103Y60520I201J0D01*
G01X1516303D01*
G02X1516504Y60319I0J-201D01*
G01Y59519D01*
G02X1516303Y59318I-201J0D01*
G01X1513103D01*
G37*
G36*
G01Y57118D02*
G02X1512902Y57319I0J201D01*
G01Y58119D01*
G02X1513103Y58320I201J0D01*
G01X1516303D01*
G02X1516504Y58119I0J-201D01*
G01Y57319D01*
G02X1516303Y57118I-201J0D01*
G01X1513103D01*
G37*
G36*
G01X1509675Y55562D02*
G02Y51738I0J-1912D01*
G01X1505174D01*
G02X1505175Y55562I1J1912D01*
G01X1509675D01*
G37*
G36*
G01X1518825Y66738D02*
G02Y70562I0J1912D01*
G01X1523826D01*
G02X1523825Y66738I-1J-1912D01*
G01X1518825D01*
G37*
G36*
G01X1513103Y512074D02*
G02X1512902Y512275I0J201D01*
G01Y513075D01*
G02X1513103Y513276I201J0D01*
G01X1516303D01*
G02X1516504Y513075I0J-201D01*
G01Y512275D01*
G02X1516303Y512074I-201J0D01*
G01X1513103D01*
G37*
G36*
G01Y509874D02*
G02X1512902Y510075I0J201D01*
G01Y510875D01*
G02X1513103Y511076I201J0D01*
G01X1516303D01*
G02X1516504Y510875I0J-201D01*
G01Y510075D01*
G02X1516303Y509874I-201J0D01*
G01X1513103D01*
G37*
G36*
G01X1518825Y519494D02*
G02Y523318I0J1912D01*
G01X1523826D01*
G02X1523825Y519494I-1J-1912D01*
G01X1518825D01*
G37*
G36*
G01X1509675Y508318D02*
G02Y504494I0J-1912D01*
G01X1505174D01*
G02X1505175Y508318I1J1912D01*
G01X1509675D01*
G37*
G36*
G01X1513103Y964830D02*
G02X1512902Y965031I0J201D01*
G01Y965831D01*
G02X1513103Y966032I201J0D01*
G01X1516303D01*
G02X1516504Y965831I0J-201D01*
G01Y965031D01*
G02X1516303Y964830I-201J0D01*
G01X1513103D01*
G37*
G36*
G01Y962630D02*
G02X1512902Y962831I0J201D01*
G01Y963631D01*
G02X1513103Y963832I201J0D01*
G01X1516303D01*
G02X1516504Y963631I0J-201D01*
G01Y962831D01*
G02X1516303Y962630I-201J0D01*
G01X1513103D01*
G37*
G36*
G01X1520488Y981831D02*
G02X1524312I1912J0D01*
G01Y976830D01*
G02X1520488Y976831I-1912J1D01*
G01Y981831D01*
G37*
G36*
G01X1507786Y961821D02*
G02X1503964I-1911J0D01*
G01Y966322D01*
G02X1507786Y966321I1911J-1D01*
G01Y961821D01*
G37*
G36*
G01X1637316Y59318D02*
G02X1637114Y59519I-1J201D01*
G01Y60319D01*
G02X1637316Y60520I202J-1D01*
G01X1640516D01*
G02X1640718Y60319I1J-201D01*
G01Y59519D01*
G02X1640516Y59318I-202J1D01*
G01X1637316D01*
G37*
G36*
G01Y57118D02*
G02X1637114Y57319I-1J201D01*
G01Y58119D01*
G02X1637316Y58320I202J-1D01*
G01X1640516D01*
G02X1640718Y58119I1J-201D01*
G01Y57319D01*
G02X1640516Y57118I-202J1D01*
G01X1637316D01*
G37*
G36*
G01X1648038Y70562D02*
G02Y66738I0J-1912D01*
G01X1643037D01*
G02X1643038Y70562I1J1912D01*
G01X1648038D01*
G37*
G36*
G01X1633888Y55562D02*
G02Y51738I0J-1912D01*
G01X1629387D01*
G02X1629388Y55562I1J1912D01*
G01X1633888D01*
G37*
G36*
G01X1637316Y512074D02*
G02X1637114Y512275I-1J201D01*
G01Y513075D01*
G02X1637316Y513276I202J-1D01*
G01X1640516D01*
G02X1640718Y513075I1J-201D01*
G01Y512275D01*
G02X1640516Y512074I-202J1D01*
G01X1637316D01*
G37*
G36*
G01Y509874D02*
G02X1637114Y510075I-1J201D01*
G01Y510875D01*
G02X1637316Y511076I202J-1D01*
G01X1640516D01*
G02X1640718Y510875I1J-201D01*
G01Y510075D01*
G02X1640516Y509874I-202J1D01*
G01X1637316D01*
G37*
G36*
G01X1648038Y523318D02*
G02Y519494I0J-1912D01*
G01X1643037D01*
G02X1643038Y523318I1J1912D01*
G01X1648038D01*
G37*
G36*
G01X1633888Y508318D02*
G02Y504494I0J-1912D01*
G01X1629387D01*
G02X1629388Y508318I1J1912D01*
G01X1633888D01*
G37*
G36*
G01X1637316Y964830D02*
G02X1637114Y965031I-1J201D01*
G01Y965831D01*
G02X1637316Y966032I202J-1D01*
G01X1640516D01*
G02X1640718Y965831I1J-201D01*
G01Y965031D01*
G02X1640516Y964830I-202J1D01*
G01X1637316D01*
G37*
G36*
G01Y962630D02*
G02X1637114Y962831I-1J201D01*
G01Y963631D01*
G02X1637316Y963832I202J-1D01*
G01X1640516D01*
G02X1640718Y963631I1J-201D01*
G01Y962831D01*
G02X1640516Y962630I-202J1D01*
G01X1637316D01*
G37*
G36*
G01X1644702Y981831D02*
G02X1648524I1911J0D01*
G01Y976830D01*
G02X1644702Y976831I-1911J1D01*
G01Y981831D01*
G37*
G36*
G01X1632000Y962381D02*
G02X1628176I-1912J0D01*
G01Y966882D01*
G02X1632000Y966881I1912J-1D01*
G01Y962381D01*
G37*
G36*
G01X1761528Y59318D02*
G02X1761326Y59519I-1J201D01*
G01Y60319D01*
G02X1761528Y60520I202J-1D01*
G01X1764728D01*
G02X1764930Y60319I1J-201D01*
G01Y59519D01*
G02X1764728Y59318I-202J1D01*
G01X1761528D01*
G37*
G36*
G01Y57118D02*
G02X1761326Y57319I-1J201D01*
G01Y58119D01*
G02X1761528Y58320I202J-1D01*
G01X1764728D01*
G02X1764930Y58119I1J-201D01*
G01Y57319D01*
G02X1764728Y57118I-202J1D01*
G01X1761528D01*
G37*
G36*
G01X1767250Y66738D02*
G02Y70562I0J1912D01*
G01X1772251D01*
G02X1772250Y66738I-1J-1912D01*
G01X1767250D01*
G37*
G36*
G01X1758100Y55562D02*
G02Y51738I0J-1912D01*
G01X1753599D01*
G02X1753600Y55562I1J1912D01*
G01X1758100D01*
G37*
G36*
G01X1761528Y512074D02*
G02X1761326Y512275I-1J201D01*
G01Y513075D01*
G02X1761528Y513276I202J-1D01*
G01X1764728D01*
G02X1764930Y513075I1J-201D01*
G01Y512275D01*
G02X1764728Y512074I-202J1D01*
G01X1761528D01*
G37*
G36*
G01Y509874D02*
G02X1761326Y510075I-1J201D01*
G01Y510875D01*
G02X1761528Y511076I202J-1D01*
G01X1764728D01*
G02X1764930Y510875I1J-201D01*
G01Y510075D01*
G02X1764728Y509874I-202J1D01*
G01X1761528D01*
G37*
G36*
G01X1767250Y519494D02*
G02Y523318I0J1912D01*
G01X1772251D01*
G02X1772250Y519494I-1J-1912D01*
G01X1767250D01*
G37*
G36*
G01X1758100Y508318D02*
G02Y504494I0J-1912D01*
G01X1753599D01*
G02X1753600Y508318I1J1912D01*
G01X1758100D01*
G37*
G36*
G01X1761528Y964830D02*
G02X1761326Y965031I-1J201D01*
G01Y965831D01*
G02X1761528Y966032I202J-1D01*
G01X1764728D01*
G02X1764930Y965831I1J-201D01*
G01Y965031D01*
G02X1764728Y964830I-202J1D01*
G01X1761528D01*
G37*
G36*
G01Y962630D02*
G02X1761326Y962831I-1J201D01*
G01Y963631D01*
G02X1761528Y963832I202J-1D01*
G01X1764728D01*
G02X1764930Y963631I1J-201D01*
G01Y962831D01*
G02X1764728Y962630I-202J1D01*
G01X1761528D01*
G37*
G36*
G01X1768914Y981831D02*
G02X1772736I1911J0D01*
G01Y976830D01*
G02X1768914Y976831I-1911J1D01*
G01Y981831D01*
G37*
G36*
G01X1756252Y961861D02*
G02X1752428I-1912J0D01*
G01Y966362D01*
G02X1756252Y966361I1912J-1D01*
G01Y961861D01*
G37*
G36*
G01X1885741Y59318D02*
G02X1885540Y59519I0J201D01*
G01Y60319D01*
G02X1885741Y60520I201J0D01*
G01X1888941D01*
G02X1889142Y60319I0J-201D01*
G01Y59519D01*
G02X1888941Y59318I-201J0D01*
G01X1885741D01*
G37*
G36*
G01Y57118D02*
G02X1885540Y57319I0J201D01*
G01Y58119D01*
G02X1885741Y58320I201J0D01*
G01X1888941D01*
G02X1889142Y58119I0J-201D01*
G01Y57319D01*
G02X1888941Y57118I-201J0D01*
G01X1885741D01*
G37*
G36*
G01X1896463Y70562D02*
G02Y66738I0J-1912D01*
G01X1891462D01*
G02X1891463Y70562I1J1912D01*
G01X1896463D01*
G37*
G36*
G01X1882313Y55562D02*
G02Y51738I0J-1912D01*
G01X1877812D01*
G02X1877813Y55562I1J1912D01*
G01X1882313D01*
G37*
G36*
G01X1885741Y512074D02*
G02X1885540Y512275I0J201D01*
G01Y513075D01*
G02X1885741Y513276I201J0D01*
G01X1888941D01*
G02X1889142Y513075I0J-201D01*
G01Y512275D01*
G02X1888941Y512074I-201J0D01*
G01X1885741D01*
G37*
G36*
G01Y509874D02*
G02X1885540Y510075I0J201D01*
G01Y510875D01*
G02X1885741Y511076I201J0D01*
G01X1888941D01*
G02X1889142Y510875I0J-201D01*
G01Y510075D01*
G02X1888941Y509874I-201J0D01*
G01X1885741D01*
G37*
G36*
G01X1896463Y523318D02*
G02Y519494I0J-1912D01*
G01X1891462D01*
G02X1891463Y523318I1J1912D01*
G01X1896463D01*
G37*
G36*
G01X1882313Y508318D02*
G02Y504494I0J-1912D01*
G01X1877812D01*
G02X1877813Y508318I1J1912D01*
G01X1882313D01*
G37*
G36*
G01X1885741Y964830D02*
G02X1885540Y965031I0J201D01*
G01Y965831D01*
G02X1885741Y966032I201J0D01*
G01X1888941D01*
G02X1889142Y965831I0J-201D01*
G01Y965031D01*
G02X1888941Y964830I-201J0D01*
G01X1885741D01*
G37*
G36*
G01Y962630D02*
G02X1885540Y962831I0J201D01*
G01Y963631D01*
G02X1885741Y963832I201J0D01*
G01X1888941D01*
G02X1889142Y963631I0J-201D01*
G01Y962831D01*
G02X1888941Y962630I-201J0D01*
G01X1885741D01*
G37*
G36*
G01X1893126Y981831D02*
G02X1896950I1912J0D01*
G01Y976830D01*
G02X1893126Y976831I-1912J1D01*
G01Y981831D01*
G37*
G36*
G01X1880464Y961861D02*
G02X1876642I-1911J0D01*
G01Y966362D01*
G02X1880464Y966361I1911J-1D01*
G01Y961861D01*
G37*
G36*
G01X1046889Y1461228D02*
X1057718Y1450399D01*
Y1406535D01*
X1054961Y1403778D01*
X975480D01*
X969841Y1409417D01*
X943487D01*
X939822Y1413082D01*
Y1454716D01*
X945132Y1460026D01*
X969824D01*
X990640Y1480842D01*
X1017017D01*
X1025274Y1472585D01*
Y1463841D01*
X1027887Y1461228D01*
X1046889D01*
G37*
G36*
G01X733250Y1443601D02*
X705399Y1415750D01*
X666189D01*
X659903Y1422036D01*
X636329D01*
X634141Y1424224D01*
Y1467576D01*
X634126Y1467613D01*
G02Y1469387I2124J887D01*
G01X634141Y1469424D01*
Y1475260D01*
X651926Y1493045D01*
X678016D01*
X690811Y1480250D01*
X716311D01*
X728250Y1468311D01*
Y1457311D01*
X733250Y1452311D01*
Y1443601D01*
G37*
G54D56*
X1130459Y883049D03*
G54D44*
X1902756Y945020D03*
Y492264D03*
Y39508D03*
X1778543Y945020D03*
Y492264D03*
Y39508D03*
X1654331Y945020D03*
Y492264D03*
Y39508D03*
X1530118Y945020D03*
Y492264D03*
Y39508D03*
X1405906Y945020D03*
Y492264D03*
Y39508D03*
X1281693Y945020D03*
Y492264D03*
Y39508D03*
X732087Y945020D03*
Y492264D03*
Y39508D03*
X607874Y945020D03*
Y492264D03*
Y39508D03*
X483661Y945020D03*
Y492264D03*
Y39508D03*
X359449Y945020D03*
Y492264D03*
Y39508D03*
X235236Y945020D03*
Y492264D03*
Y39508D03*
X111024Y945020D03*
Y492264D03*
Y39508D03*
G54D43*
X1909941Y979331D03*
Y964331D03*
Y526575D03*
Y511575D03*
Y58819D03*
Y73819D03*
X1537303Y979331D03*
Y964331D03*
Y526575D03*
Y511575D03*
Y58819D03*
Y73819D03*
X1413091Y979331D03*
Y964331D03*
Y526575D03*
Y511575D03*
Y58819D03*
Y73819D03*
X615059Y979331D03*
Y964331D03*
Y526575D03*
Y511575D03*
Y73819D03*
Y58819D03*
X242421Y979331D03*
Y964331D03*
Y511575D03*
Y526575D03*
Y73819D03*
Y58819D03*
X118209Y979331D03*
Y964331D03*
Y526575D03*
Y511575D03*
Y73819D03*
Y58819D03*
G54D48*
X1785728Y979331D03*
Y964331D03*
Y526575D03*
Y511575D03*
Y58819D03*
Y73819D03*
X1661516Y979331D03*
Y964331D03*
Y526575D03*
Y511575D03*
Y58819D03*
Y73819D03*
X1288878Y979331D03*
Y964331D03*
Y526575D03*
Y511575D03*
Y58819D03*
Y73819D03*
X739272Y979331D03*
Y964331D03*
Y526575D03*
Y511575D03*
Y73819D03*
Y58819D03*
X490846Y979331D03*
Y964331D03*
Y526575D03*
Y511575D03*
Y73819D03*
Y58819D03*
X366634Y979331D03*
Y964331D03*
Y526575D03*
Y511575D03*
Y73819D03*
Y58819D03*
G54D42*
X1902756Y1093642D03*
Y640886D03*
Y188130D03*
X1778543Y1093642D03*
Y640886D03*
Y188130D03*
X1654331Y1093642D03*
Y640886D03*
Y188130D03*
X1530118Y1093642D03*
Y640886D03*
Y188130D03*
X1405906Y1093642D03*
Y640886D03*
Y188130D03*
X1281693Y1093642D03*
Y640886D03*
Y188130D03*
X732087Y1093642D03*
Y640886D03*
Y188130D03*
X607874Y1093642D03*
Y640886D03*
Y188130D03*
X483661Y1093642D03*
Y640886D03*
Y188130D03*
X359449Y1093642D03*
Y640886D03*
Y188130D03*
X235236Y1093642D03*
Y640886D03*
Y188130D03*
X111024Y1093642D03*
Y640886D03*
Y188130D03*
G54D51*
X256535Y1320472D03*
G54D41*
X1869500Y1461500D03*
X63374Y1454500D03*
X59400Y32600D03*
G54D47*
X1761417Y1495669D03*
X1695275D03*
X1381102D03*
X1314960D03*
X614173D03*
X548031D03*
X233858D03*
X167716D03*
G54D45*
X1840551Y122046D03*
X1343701D03*
X670079Y122047D03*
X173228D03*
G54D46*
X1840551Y55118D03*
X1343701D03*
X670078D03*
X421653Y94488D03*
X173228Y55118D03*
G54D49*
X1104527Y1162258D03*
G54D52*
X627263Y262981D03*
Y715737D03*
Y1168492D03*
X961417Y703925D03*
Y972429D03*
X1181889Y381878D03*
Y972429D03*
X1549901Y262981D03*
Y715737D03*
Y1168492D03*
X1797933Y262980D03*
Y715737D03*
Y1168492D03*
G54D53*
X1098176Y520057D03*
Y548403D03*
X1102113Y527143D03*
Y569663D03*
X1126522Y548403D03*
X1130459Y541317D03*
Y527143D03*
X1126522Y520057D03*
X1116286Y569663D03*
X1130459D03*
X1098176Y691711D03*
X1102113Y698797D03*
Y741317D03*
X1098176Y748403D03*
Y720057D03*
Y762577D03*
X1126522Y691711D03*
X1130459Y698797D03*
Y741317D03*
X1126522Y748403D03*
Y720057D03*
Y762577D03*
X1102113Y769663D03*
X1098176Y790923D03*
Y833443D03*
X1102113Y840529D03*
Y854703D03*
Y812183D03*
X1130459Y769663D03*
X1126522Y790923D03*
Y833443D03*
X1130459Y840529D03*
Y854703D03*
Y812183D03*
X1098176Y904309D03*
Y861789D03*
X1102113Y883049D03*
Y925569D03*
X1098176Y932655D03*
X1126522Y904309D03*
Y861789D03*
X1130459Y925569D03*
X1126522Y932655D03*
G54D50*
X131200Y262981D03*
Y715737D03*
Y1168492D03*
X379232Y262981D03*
Y715737D03*
Y1168492D03*
X747244Y381878D03*
Y814949D03*
X1301870Y262980D03*
Y715737D03*
Y1168492D03*
G54D55*
X1102113Y541317D03*
G54D54*
X1098176Y562576D03*
X1102113Y555490D03*
X1098176Y534230D03*
X1126522Y562576D03*
X1130459Y555490D03*
X1126522Y534230D03*
X1098176Y705884D03*
Y734230D03*
X1102113Y755490D03*
Y712970D03*
Y727144D03*
X1126522Y705884D03*
Y734230D03*
X1130459Y755490D03*
Y712970D03*
Y727144D03*
X1098176Y805096D03*
X1102113Y798010D03*
Y783836D03*
X1098176Y776750D03*
Y819270D03*
X1102113Y826356D03*
X1098176Y847616D03*
X1126522Y776750D03*
X1130459Y783836D03*
Y798010D03*
X1126522Y805096D03*
Y819270D03*
X1130459Y826356D03*
X1126522Y847616D03*
X1102113Y868876D03*
Y897222D03*
X1098176Y890136D03*
Y875962D03*
X1102113Y911396D03*
X1098176Y918482D03*
X1102113Y939742D03*
X1130459Y868876D03*
X1126522Y875962D03*
X1130459Y897222D03*
X1126522Y890136D03*
X1130459Y911396D03*
X1126522Y918482D03*
X1130459Y939742D03*
%LPC*%
G75*
G36*
G01X599811Y1288250D02*
X597750Y1290311D01*
Y1302811D01*
X595837Y1304724D01*
X536520D01*
G02X536396Y1305504I0J400D01*
G03X531496Y1336222I-4900J14968D01*
G01X511496D01*
G03X506596Y1305504I0J-15750D01*
G02X506472Y1304724I-124J-380D01*
G01X410337D01*
X405250Y1309811D01*
Y1362689D01*
X408750Y1366189D01*
Y1433822D01*
X409933Y1435005D01*
X429967D01*
X441452Y1423520D01*
X484236D01*
X497506Y1410250D01*
X632250D01*
Y1295750D01*
X621689D01*
X619750Y1293811D01*
Y1288811D01*
X619189Y1288250D01*
X599811D01*
G37*
G36*
G01X803739Y1295750D02*
X655100D01*
Y1410250D01*
X803589D01*
X804900Y1408939D01*
Y1296911D01*
X803739Y1295750D01*
G37*
G36*
G01X704777Y1417250D02*
X666811D01*
X660525Y1423536D01*
X636951D01*
X635641Y1424846D01*
Y1474638D01*
X652548Y1491545D01*
X677394D01*
X690189Y1478750D01*
X715689D01*
X726750Y1467689D01*
Y1456689D01*
X731750Y1451689D01*
Y1444223D01*
X704777Y1417250D01*
G37*
G36*
G01X1054339Y1405278D02*
X976102D01*
X970463Y1410917D01*
X944109D01*
X941322Y1413704D01*
Y1454094D01*
X945754Y1458526D01*
X970446D01*
X991262Y1479342D01*
X1016395D01*
X1023774Y1471963D01*
Y1463219D01*
X1027265Y1459728D01*
X1046267D01*
X1056218Y1449777D01*
Y1407157D01*
X1054339Y1405278D01*
G37*
%LPD*%
G75*
G54D36*
X834000Y1324500D03*
Y1317500D03*
Y1310500D03*
Y1303500D03*
X827000D03*
X820000D03*
X827000Y1310500D03*
X820000D03*
X827000Y1317500D03*
X820000D03*
X827000Y1324500D03*
X820000D03*
X834000Y1386000D03*
Y1379000D03*
Y1363000D03*
Y1356000D03*
Y1349000D03*
Y1342000D03*
X827000D03*
X820000D03*
X827000Y1349000D03*
X820000D03*
X827000Y1356000D03*
X820000D03*
X827000Y1363000D03*
X820000D03*
X827000Y1379000D03*
X820000D03*
X827000Y1386000D03*
X820000D03*
X827000Y1393000D03*
X820000D03*
X958200Y1303900D03*
X942400D03*
X950300D03*
X934500D03*
X926600D03*
X958200Y1311800D03*
X926600D03*
X934500D03*
X950300D03*
X942400D03*
X903500Y1319400D03*
X950300Y1319700D03*
X958200D03*
X934500D03*
X942400D03*
X926600D03*
X918700D03*
X910800D03*
X887800Y1327100D03*
X934700Y1327500D03*
X895200D03*
X903100D03*
X911000D03*
X926800D03*
X918900D03*
X887800Y1335000D03*
X886400Y1368100D03*
Y1376000D03*
X894300D03*
Y1368100D03*
X934700Y1335400D03*
X926800D03*
X918900D03*
X895200D03*
X903100D03*
X911000D03*
X890400Y1358900D03*
X887800Y1350800D03*
Y1342900D03*
X937300Y1359300D03*
X934700Y1343300D03*
Y1351200D03*
X926800Y1343300D03*
Y1351200D03*
X929400Y1359300D03*
X918900Y1343300D03*
Y1351200D03*
X921500Y1359300D03*
X918000Y1368100D03*
Y1376000D03*
X910100Y1368100D03*
Y1376000D03*
X911000Y1343300D03*
Y1351200D03*
X913600Y1359300D03*
X903100Y1343300D03*
Y1351200D03*
X905700Y1359300D03*
X902200Y1376000D03*
Y1368100D03*
X897800Y1359300D03*
X895200Y1351200D03*
Y1343300D03*
X998600Y1300900D03*
X991500Y1312100D03*
X1020800Y1300400D03*
X991455Y1320416D03*
X996400Y1315900D03*
X996200Y1307800D03*
X1014000Y1300600D03*
X991755Y1327716D03*
X996055Y1324116D03*
X1007100Y1301100D03*
X1011100Y1305300D03*
X1019829Y1306139D03*
X1002700Y1305700D03*
X991800Y1303400D03*
X1000200Y1311700D03*
Y1320500D03*
X1016429Y1333939D03*
X1021829D03*
X1011029D03*
X1005629D03*
X986755Y1323816D03*
X986700Y1307600D03*
X1000200Y1328100D03*
X1050818Y1311189D03*
Y1316589D03*
X1045418Y1321989D03*
X1050818D03*
X1034618Y1311189D03*
X1040018D03*
X1045418D03*
X1040018Y1316589D03*
X1034618D03*
X1040018Y1321989D03*
X1031600Y1335100D03*
X1037200Y1335000D03*
X1034618Y1321989D03*
X997900Y1335800D03*
X992500D03*
X997900Y1341200D03*
X992500D03*
X997900Y1346600D03*
X992500D03*
X997900Y1352000D03*
X992500D03*
Y1357400D03*
X997900D03*
X989083Y1387764D03*
X989509Y1393422D03*
X994700Y1385000D03*
X999700Y1374500D03*
X989100Y1381700D03*
X994200Y1362700D03*
X1019829Y1389539D03*
X1013692Y1389688D03*
X1019829Y1361739D03*
X1014306Y1361710D03*
X1008870Y1361681D03*
X1003367Y1361655D03*
X1004217Y1389394D03*
X1008298Y1393071D03*
X994400Y1377300D03*
X999930Y1393070D03*
X999800Y1381600D03*
X999900Y1366800D03*
X994300Y1370100D03*
X989200Y1374800D03*
X988900Y1366900D03*
X1034600Y1349600D03*
X1042400Y1349500D03*
X1037540Y1344964D03*
X1034799Y1340183D03*
X1044700Y1335500D03*
X1043300Y1342500D03*
X1048000Y1346100D03*
X1037111Y1372380D03*
X1039988Y1367352D03*
X1044400Y1363100D03*
X1036900Y1362600D03*
X1034380Y1367469D03*
X1031300Y1362700D03*
X1042100Y1377100D03*
X1034300Y1377200D03*
X1047401Y1375084D03*
X1066481Y1327759D03*
X1061081D03*
X1066481Y1333159D03*
X1061081D03*
X1061618Y1316589D03*
X1056218Y1311189D03*
X1061618D03*
X1056218Y1316589D03*
X1060218Y1321989D03*
X1066491Y1319983D03*
X1066407Y1313972D03*
X1066481Y1338559D03*
X1061081D03*
X1066481Y1343959D03*
X1061081D03*
X1066481Y1376359D03*
Y1349359D03*
Y1354759D03*
Y1360159D03*
Y1365559D03*
Y1370959D03*
X1061081Y1376359D03*
Y1370959D03*
Y1365559D03*
Y1360159D03*
Y1354759D03*
Y1349359D03*
G54D12*
X92500Y62800D03*
X56750Y62000D03*
X64250Y87500D03*
X95800Y71800D03*
X30500Y67000D03*
X74000Y87500D03*
X89000D03*
X84000D03*
X79000D03*
X50000Y105500D03*
X54500D03*
X59000D03*
X58709Y372346D03*
X84581Y397946D03*
X79581D03*
X93800Y516800D03*
X64250Y540000D03*
X50000Y558000D03*
X54500D03*
X59000D03*
X53250Y518000D03*
X95500Y525500D03*
X79000Y540000D03*
X84000D03*
X89000D03*
X74000D03*
X46442Y825000D03*
X73526Y850100D03*
X68526D03*
X83300Y908900D03*
X100310Y899557D03*
X68900Y897700D03*
X77263Y898225D03*
X83500Y898662D03*
X73430Y898509D03*
X70603Y887495D03*
X66263Y879525D03*
X67763Y883525D03*
X95500Y968000D03*
X59000Y1011000D03*
X54500D03*
X50000D03*
X64250Y993000D03*
X53250Y971000D03*
X95500Y972500D03*
X74000Y993000D03*
X89000D03*
X84000D03*
X79000D03*
X183500Y75450D03*
Y80250D03*
X178500Y80000D03*
X185551Y21529D03*
X151200Y48500D03*
Y44400D03*
X145864Y33216D03*
X175650Y28600D03*
X131600Y119100D03*
X192842Y372000D03*
X181127Y471164D03*
X166727Y459964D03*
X175090Y460489D03*
X181327Y460926D03*
X171257Y460773D03*
X168430Y449759D03*
X165590Y445789D03*
X164127Y442264D03*
X188250Y540000D03*
X176439Y524992D03*
X182300Y558600D03*
X173600Y554400D03*
Y558600D03*
X178100D03*
X176506Y539295D03*
X143000Y587000D03*
X169442Y824700D03*
X191026Y850100D03*
X196026D03*
X102263Y919025D03*
X114563Y904041D03*
X113763Y865025D03*
X106263Y900025D03*
X106363Y893425D03*
X102207Y890524D03*
X183500Y1011000D03*
X179000D03*
X174500D03*
X188750Y993000D03*
X178200Y977700D03*
X140750Y1039250D03*
X125500Y992500D03*
X130601Y1411700D03*
X136774Y1411000D03*
X188274Y1416600D03*
X165774Y1422700D03*
X124874Y1442600D03*
X151874Y1449800D03*
X149955Y1431573D03*
X135374Y1464000D03*
Y1445500D03*
X105774Y1491000D03*
X120474Y1482800D03*
X132674Y1484200D03*
X137624Y1469000D03*
X175249Y1434075D03*
X156374Y1430500D03*
X130322Y1434014D03*
X135174Y1452400D03*
X104184Y1457200D03*
X139374Y1486100D03*
X124074Y1437200D03*
X113314Y1441700D03*
X220000Y80500D03*
X200819Y74819D03*
X217000Y38250D03*
X198800Y34000D03*
X203078Y33972D03*
X215500Y80500D03*
X203000Y87500D03*
X213000D03*
X208000D03*
X197500D03*
X254900Y119600D03*
X218214Y397600D03*
X213214D03*
X212390Y466305D03*
X198137Y461821D03*
X204090Y462289D03*
X204190Y455689D03*
X200022Y452941D03*
X218000Y516600D03*
X200090Y481289D03*
X220000Y524000D03*
X203000Y540000D03*
X208000D03*
X213000D03*
X198000D03*
X264750Y586250D03*
X197263Y901025D03*
X218100Y969700D03*
X264450Y1039250D03*
X252000Y992500D03*
X220000Y978200D03*
X198500Y993000D03*
X213500D03*
X208500D03*
X203500D03*
X209374Y1416300D03*
X341800Y63700D03*
X311800Y83700D03*
X301750Y65500D03*
X340650Y69300D03*
X327500Y87500D03*
X332500D03*
X337500D03*
X322500D03*
X293700Y105500D03*
X298500D03*
X302999Y105501D03*
X379500Y119500D03*
X294542Y372300D03*
X320514Y397600D03*
X315514D03*
X295090Y463289D03*
X341800Y516800D03*
X312750Y536300D03*
X299104Y556943D03*
X303604D03*
X308104D03*
X301750Y518000D03*
X344000Y525300D03*
X322500Y540000D03*
X337500D03*
X332500D03*
X327500D03*
X294542Y825000D03*
X320526Y850100D03*
X315526D03*
X341900Y969400D03*
X307500Y1011000D03*
X303000D03*
X298500D03*
X312750Y993000D03*
X302100Y978200D03*
X376000Y993000D03*
X344200Y978200D03*
X322500Y993000D03*
X337500D03*
X332500D03*
X327500D03*
X425500Y72600D03*
X435500D03*
X430500D03*
X440500D03*
X468500Y80500D03*
X465500Y38250D03*
X425500Y41250D03*
X430500D03*
X434804Y41242D03*
X444663Y32417D03*
X440400Y32400D03*
X464000Y80500D03*
X446400Y91100D03*
X456900D03*
X461900D03*
X451900D03*
X437500Y134500D03*
X441500D03*
X433500D03*
X430083Y122357D03*
X419042Y372000D03*
X445014Y397600D03*
X440014D03*
X466000Y516900D03*
X436750Y538400D03*
X422500Y558000D03*
X427000D03*
X431500D03*
X429210Y512992D03*
X464801Y521156D03*
X446500Y540000D03*
X461500D03*
X456500D03*
X451500D03*
X390632Y588624D03*
X418742Y824444D03*
X440026Y850100D03*
X445026D03*
X466100Y969200D03*
X431500Y1011000D03*
X427000D03*
X422500D03*
X436750Y993000D03*
X426300Y976800D03*
X389250Y1039250D03*
X468300Y978000D03*
X446500Y993000D03*
X461500D03*
X456500D03*
X451500D03*
X561250Y87500D03*
X550250Y65500D03*
X576000Y87500D03*
X571000D03*
X547000Y105500D03*
X551500D03*
X556000D03*
X503900Y119500D03*
X543242Y372300D03*
X569014Y397600D03*
X564014D03*
X561250Y540000D03*
X550250Y518000D03*
X571000Y540000D03*
X576000D03*
X516000Y637413D03*
X546500Y572000D03*
X551044Y572149D03*
X555321Y572375D03*
X517999Y583015D03*
X564026Y850100D03*
X569026D03*
X556000Y1011000D03*
X551500D03*
X547000D03*
X561250Y993000D03*
X550700Y979500D03*
X513250Y1039250D03*
X500000Y992000D03*
X571000Y993000D03*
X576000D03*
X523455Y1416564D03*
X535200Y1466100D03*
X523500Y1455400D03*
X503001Y1454922D03*
X513624Y1458624D03*
X504000Y1470500D03*
X503035Y1444331D03*
X528250Y1470900D03*
X496500Y1476000D03*
X508867Y1497771D03*
X590600Y64300D03*
X670500Y80000D03*
X589150Y69500D03*
X581000Y87500D03*
X586000D03*
X628000Y119500D03*
X654242Y372000D03*
X583550Y504600D03*
X672018Y557014D03*
X592500Y525300D03*
X586000Y540000D03*
X581000D03*
X664651Y513000D03*
X666900Y665400D03*
X637750Y586250D03*
X646680Y679430D03*
X582648Y825223D03*
X659642Y824700D03*
X585904Y900960D03*
X589904D03*
X593904D03*
X597904D03*
X601904D03*
X673000Y885500D03*
X590200Y969500D03*
X671000Y1011000D03*
X624500Y993000D03*
X592800Y978100D03*
X586000Y993000D03*
X581000D03*
X646102Y1321750D03*
X641102D03*
X646200Y1420576D03*
X641200D03*
X637971Y1425400D03*
X653000Y1488500D03*
X665700Y1463500D03*
Y1468500D03*
X650000Y1464052D03*
Y1467948D03*
Y1457448D03*
Y1453552D03*
X636250Y1468500D03*
X628500D03*
X637972Y1441419D03*
X658000Y1444000D03*
X665700Y1458000D03*
Y1453000D03*
X624750Y1461250D03*
X712214Y82500D03*
X680500Y80250D03*
X675500Y80000D03*
X697787Y74488D03*
X714000Y38250D03*
X695600Y34000D03*
X699932Y34034D03*
X709000Y79500D03*
X700000Y87500D03*
X705000D03*
X710000D03*
X694500D03*
X711352Y26875D03*
X715205Y27012D03*
X705171Y16254D03*
X753473Y138459D03*
X685514Y397600D03*
X680514D03*
X698600Y511100D03*
X685250Y540000D03*
X680902Y557860D03*
X676402D03*
X674250Y518000D03*
X714600Y498100D03*
X716400Y525200D03*
X695000Y540000D03*
X700000D03*
X705000D03*
X710000D03*
X752200Y572300D03*
X709871Y686246D03*
X718100Y738500D03*
X718200Y744000D03*
X723000Y739200D03*
X723300Y743700D03*
X728175Y741300D03*
X728100Y745500D03*
X680526Y850100D03*
X685526D03*
X701700Y872700D03*
X714500Y870100D03*
X723600Y872400D03*
X712760Y915137D03*
X727600Y872300D03*
X733895Y901054D03*
X754000Y884524D03*
X757600Y884400D03*
X677000Y885500D03*
X714400Y969600D03*
X680000Y1011000D03*
X675500D03*
X685250Y993000D03*
X675400Y980500D03*
X755200Y992400D03*
X716800Y978300D03*
X700000Y993000D03*
X705000D03*
X710000D03*
X695000D03*
X759249Y1008800D03*
X759700Y1138600D03*
X759762Y1135000D03*
X742880Y1422632D03*
X739532Y1425934D03*
X724248Y1465560D03*
X730500Y1451500D03*
X685850Y1468600D03*
X724000Y1439700D03*
X717600Y1449700D03*
X680900Y1469200D03*
X680200Y1465500D03*
X675550Y1458721D03*
Y1452216D03*
X692000Y1471156D03*
X689250Y1433500D03*
X681250D03*
X745000Y1463000D03*
X730341Y1446725D03*
X756332Y1465934D03*
X745032Y1468534D03*
X732232Y1477094D03*
X718900Y1472800D03*
X679800Y1483500D03*
X708600Y1469900D03*
X724066Y1461018D03*
X724255Y1457253D03*
X735232Y1451210D03*
X835165Y470414D03*
X787971Y466121D03*
X791971D03*
X787971Y461921D03*
X791971D03*
X787971Y457721D03*
X791971D03*
X848799Y457202D03*
X849539Y453596D03*
X827313Y464805D03*
X827361Y459317D03*
X860519Y428234D03*
X860716Y417600D03*
X850947Y417592D03*
X832417Y459017D03*
X812282Y448094D03*
X815255Y451343D03*
X808395Y454315D03*
X858740Y486430D03*
X794883Y639984D03*
X798475Y640227D03*
X863430Y618590D03*
X788160Y666220D03*
X814320Y651120D03*
X813980Y647430D03*
X860360Y605900D03*
X836862Y637500D03*
X815148Y654937D03*
X824618Y614617D03*
X827750Y611798D03*
X791530Y614700D03*
X791680Y619050D03*
X799900Y636300D03*
X807440Y629910D03*
X802900Y634000D03*
X837709Y681095D03*
X789442Y681063D03*
X796200Y682400D03*
X791243Y668081D03*
X778627Y735644D03*
X778683Y745049D03*
X778735Y839888D03*
X791500Y764500D03*
X795300Y764900D03*
X826000Y857400D03*
X815469Y811029D03*
X815330Y807050D03*
X818113Y814998D03*
X834200Y796220D03*
X810700Y772000D03*
Y781000D03*
X858500Y845700D03*
X858100Y850000D03*
X848300Y847700D03*
X804200Y798200D03*
X811372Y795900D03*
X808372Y797900D03*
X805372Y801700D03*
X825900Y862040D03*
X801300Y924300D03*
X799303Y927296D03*
X822463Y920345D03*
X842270Y936402D03*
X861300Y895300D03*
X819000Y896100D03*
X817337Y886075D03*
X815400Y892800D03*
X844800Y895902D03*
X845732Y891713D03*
X839970Y981470D03*
X834470D03*
X826470D03*
X848400Y974100D03*
X836953Y1023500D03*
X842700Y1071900D03*
X782712Y1211404D03*
Y1206904D03*
X772601Y1223511D03*
Y1219011D03*
Y1214511D03*
X777101Y1223511D03*
X832800Y1147500D03*
X795100Y1150400D03*
X798920Y1150500D03*
X821900Y1173700D03*
X773300Y1159700D03*
X769800Y1156500D03*
X776800Y1169700D03*
X780722Y1166357D03*
X780000Y1162800D03*
X822500Y1331000D03*
Y1298000D03*
Y1294000D03*
X852000Y1402000D03*
Y1406000D03*
X822500Y1373500D03*
Y1369500D03*
X835000Y1402500D03*
Y1398000D03*
X822500Y1335000D03*
X772361Y1451972D03*
X882823Y331182D03*
X909236Y333242D03*
X906486Y330524D03*
X910330Y363490D03*
X908340Y360430D03*
X909423Y354393D03*
X898059Y343029D03*
X902184Y347219D03*
X906616Y351586D03*
X922800Y362400D03*
X922700Y358100D03*
X945408Y378761D03*
X950843Y378827D03*
X871591Y431161D03*
X870400Y454315D03*
X867299Y493300D03*
Y497200D03*
X922525Y519833D03*
X873000Y494100D03*
X929096Y517567D03*
X873200Y487300D03*
X944387Y520100D03*
X941557Y547005D03*
X955000Y540800D03*
X935477Y524023D03*
X938338Y529107D03*
X938579Y551379D03*
X938623Y556600D03*
X956100Y516500D03*
X867299Y508600D03*
Y504700D03*
X935490Y519550D03*
X884801Y630225D03*
X892400Y633700D03*
X878740Y643190D03*
Y651190D03*
X870200Y631500D03*
X867260Y608600D03*
X883030Y611940D03*
X878600Y615600D03*
X879600Y621600D03*
X878400Y626200D03*
X874706Y752583D03*
X924484Y812558D03*
X921047Y811463D03*
X869989Y818847D03*
X931800Y791500D03*
X870001Y822862D03*
X934800Y795300D03*
X916855Y810934D03*
X909144Y803346D03*
X903700Y803200D03*
X912762Y792801D03*
X903221Y793938D03*
X912030Y787650D03*
X907800Y788700D03*
X913059Y810367D03*
X906166Y812784D03*
X902560Y813313D03*
X876862Y842155D03*
X881702Y838859D03*
X874593Y763800D03*
X874821Y767690D03*
X931380Y821500D03*
X935485Y821400D03*
X903572Y773740D03*
X931206Y845756D03*
X920170Y857430D03*
X903500Y769900D03*
X939500Y842400D03*
X924670Y857430D03*
X953000Y842400D03*
X911080Y857420D03*
X948500Y842400D03*
X881216Y813813D03*
X910807Y766589D03*
X904484Y786109D03*
X876256Y798895D03*
X874500Y779100D03*
X866655Y855100D03*
X870200Y852203D03*
X872600Y798700D03*
X943294Y838833D03*
X903300Y763200D03*
X894317Y865406D03*
X890117D03*
X894317Y861206D03*
X890117D03*
X879667Y877303D03*
X884684Y877406D03*
X927260Y922470D03*
X909760Y925445D03*
X922760Y922470D03*
X958256Y894438D03*
X930310Y858550D03*
X879770Y868369D03*
X895500Y1038000D03*
X891600Y980000D03*
X888000D03*
X886400Y976500D03*
X893600D03*
X897200D03*
X895200Y980000D03*
X890000Y976500D03*
X951500Y1117500D03*
X947000D03*
X943000D03*
X949500Y1114500D03*
X954500D03*
X956500Y1117500D03*
X890500Y1201200D03*
X885930Y1210537D03*
X892460Y1211340D03*
X887200Y1216460D03*
X893200Y1203660D03*
X888825Y1208263D03*
X889965Y1213936D03*
X884677Y1219029D03*
X947700Y1185500D03*
X947500Y1233000D03*
X955500D03*
X926700Y1199000D03*
X952500Y1193300D03*
X869937Y1400312D03*
X941559Y1408198D03*
Y1403198D03*
X866000Y1398000D03*
X945415Y1429318D03*
X945414Y1412818D03*
X944019Y1452220D03*
X1038067Y441886D03*
X1021890Y439717D03*
X991538Y522018D03*
X1000051Y547644D03*
X974530Y559550D03*
X974550Y563690D03*
X1003591Y552081D03*
X996998Y539555D03*
X971420Y537950D03*
X975910Y537770D03*
X990200Y544250D03*
X995213Y529837D03*
X998905Y529824D03*
X986638Y519684D03*
X991360Y529780D03*
X963870Y754152D03*
X1050774Y815327D03*
X1050650Y825420D03*
X1022838Y829101D03*
X1042545Y832026D03*
X1015950Y838000D03*
X1026932Y841614D03*
X1050082Y843729D03*
X993400Y833250D03*
X969926Y847638D03*
X971197Y775799D03*
X977676Y828513D03*
X1005272Y837091D03*
X1000827Y837072D03*
X973070Y828512D03*
X1027524Y948954D03*
X1039500Y891100D03*
X1037110Y859471D03*
X989100Y899600D03*
X972042Y884600D03*
X985542Y882900D03*
X989742D03*
X996938Y901170D03*
X1034200Y945000D03*
X1040200D03*
X1046272Y944928D03*
X1039500Y874700D03*
X1024129Y946152D03*
X1044800Y893750D03*
X1030862Y951946D03*
X1022080Y960728D03*
X1008739Y1096000D03*
X961000Y1117500D03*
X1029500Y1104900D03*
X1028500Y1118601D03*
X1030178Y1134165D03*
X965500Y1128000D03*
X1012800Y1122100D03*
X1002671Y1124700D03*
X1029000Y1122400D03*
X977643Y1132490D03*
X1007431Y1122900D03*
X1026100Y1145996D03*
X1014500Y1153500D03*
X1012000Y1150000D03*
X1017500D03*
X1020000Y1153500D03*
X982500Y1201000D03*
Y1197000D03*
Y1213000D03*
Y1221000D03*
Y1225000D03*
Y1205000D03*
X964550Y1190200D03*
X1054918Y1330439D03*
Y1325739D03*
X1035943Y1424649D03*
X1031443Y1426899D03*
X1040127Y1422500D03*
X1033287Y1410500D03*
X1037400Y1400600D03*
X1031400Y1399200D03*
X1054918Y1386039D03*
Y1353539D03*
Y1358239D03*
Y1381339D03*
X966985Y1393900D03*
X961857D03*
X996693Y1421399D03*
X988693D03*
X1047000Y1421800D03*
X1039900Y1417000D03*
X1038303Y1441709D03*
X1021818Y1470865D03*
X1021693Y1444649D03*
X993100Y1456550D03*
X1007618Y1477365D03*
X1013418Y1470865D03*
X987576Y1451454D03*
Y1455054D03*
X982343Y1446620D03*
Y1440115D03*
X961877Y1445347D03*
Y1441451D03*
X999443Y1458006D03*
X1049260Y1466691D03*
X1017618Y1470865D03*
X993830Y1471364D03*
X1017618Y1460865D03*
X1043606Y1437906D03*
X962136Y1431831D03*
X1033253Y1444649D03*
X1048553Y1448399D03*
X1035526Y1455899D03*
X1041176Y1455500D03*
X1020500Y1500014D03*
X1037550Y1475814D03*
X1136100Y460288D03*
X1147440Y473040D03*
X1143720Y468520D03*
X1143420Y472900D03*
X1139590Y468380D03*
X1139330Y472820D03*
X1135410Y468380D03*
X1135310Y472820D03*
X1130800Y472900D03*
X1131800Y446800D03*
X1136000Y446849D03*
X1092000Y448400D03*
X1088000Y448500D03*
X1103100Y457300D03*
X1095100Y455800D03*
X1113593Y476094D03*
X1149964Y481623D03*
X1102677Y487116D03*
X1119242Y477261D03*
X1134600Y618747D03*
X1118505Y658863D03*
X1114905Y658882D03*
X1129500Y619200D03*
X1138900Y584900D03*
X1125025Y621993D03*
X1056116Y697100D03*
X1057826Y680233D03*
X1059927Y688329D03*
X1064216Y683751D03*
X1067554Y694447D03*
X1071179Y682315D03*
X1112682Y681223D03*
X1107674Y677776D03*
X1141230Y673825D03*
X1103770Y675413D03*
X1075706Y941261D03*
X1141370Y905550D03*
X1058800Y893750D03*
X1093588Y972000D03*
X1110600Y964200D03*
X1108500Y960600D03*
X1104600Y967800D03*
X1101950Y962900D03*
X1101600Y953700D03*
X1087962Y959252D03*
X1068569Y1191530D03*
X1072931Y1191482D03*
X1072900Y1204500D03*
X1084571Y1200129D03*
X1072600Y1211400D03*
X1084400Y1204200D03*
X1083100Y1305600D03*
X1082080Y1299375D03*
X1126820Y1288500D03*
X1075030Y1323078D03*
X1078850Y1287900D03*
X1082080Y1309495D03*
X1123000Y1297600D03*
X1096280Y1288150D03*
X1092475Y1287971D03*
X1133480Y1296700D03*
Y1291700D03*
X1121346Y1307385D03*
Y1311385D03*
X1117000Y1332500D03*
Y1328500D03*
X1072120Y1299375D03*
Y1304495D03*
Y1309495D03*
Y1292460D03*
X1067712Y1384766D03*
X1099112Y1391273D03*
X1099100Y1375200D03*
X1099112Y1383273D03*
X1099100Y1371200D03*
X1117362Y1406073D03*
X1134112Y1363273D03*
X1122112D03*
X1091000Y1393500D03*
X1086646Y1396419D03*
X1126112Y1401773D03*
X1160900Y468500D03*
X1156110Y473330D03*
X1152600Y468470D03*
X1245567Y420602D03*
X1243500Y393600D03*
X1201000Y447000D03*
X1200500Y452000D03*
X1150900Y485100D03*
X1177100Y495300D03*
X1167000Y586500D03*
X1232490Y664290D03*
X1236690D03*
X1171700Y603700D03*
X1172500Y599700D03*
X1169125Y581776D03*
X1166550Y579200D03*
X1177350Y597792D03*
X1212587Y740895D03*
Y736695D03*
Y732495D03*
X1232490Y668490D03*
X1212587Y728295D03*
X1236690Y668490D03*
X1212587Y724095D03*
X1232490Y672690D03*
X1212587Y719895D03*
X1236690Y672690D03*
X1206414Y704261D03*
X1209931Y701608D03*
X1207468Y697962D03*
X1210283Y695565D03*
X1212587Y749295D03*
Y745095D03*
X1232490Y685290D03*
X1179129Y672187D03*
X1232490Y681090D03*
X1190995Y776395D03*
X1186690Y791440D03*
X1217111Y825000D03*
X1173990Y797760D03*
X1177300Y804960D03*
X1180520Y790880D03*
X1179690Y798020D03*
X1157556Y932754D03*
X1184778Y912848D03*
X1180090Y896524D03*
X1181550Y906100D03*
X1184750Y889200D03*
Y896300D03*
X1155600Y1074500D03*
X1193894Y1292533D03*
X1227100D03*
X1205624D03*
X1238830D03*
X1185324Y1286563D03*
X1220450Y1292533D03*
X1216894Y1304283D03*
Y1308283D03*
X1183894Y1304783D03*
Y1308783D03*
X1188894Y1346763D03*
X1222000Y1346700D03*
X1180614Y1340033D03*
X1213820D03*
X1243768Y1376953D03*
X1208394Y1346763D03*
X1193894D03*
X1227100D03*
X1203312Y1402793D03*
X1241600Y1346763D03*
X1169412Y1396873D03*
X1297000Y68500D03*
X1319100Y47400D03*
X1308000Y35000D03*
X1309500Y76500D03*
X1314500D03*
X1299500D03*
X1304500D03*
X1261100Y16600D03*
X1264700Y16400D03*
X1256800Y132400D03*
X1322500Y113500D03*
X1317500D03*
X1327000D03*
X1262600Y119700D03*
X1262945Y377600D03*
X1294624Y358802D03*
X1247949Y423302D03*
X1250648Y425686D03*
X1245959Y435527D03*
X1265295Y421223D03*
X1257000Y434600D03*
X1248500Y393600D03*
X1325500Y504750D03*
X1323000Y566500D03*
X1318000D03*
X1328000D03*
X1300100Y530000D03*
X1326500Y514000D03*
X1312000Y501500D03*
X1272182Y571361D03*
X1334500Y549500D03*
Y554500D03*
Y539500D03*
Y544500D03*
X1247588Y842190D03*
X1325500Y907000D03*
Y957250D03*
X1323000Y1019000D03*
X1318000D03*
X1328000D03*
X1300900Y981800D03*
X1326500Y966500D03*
X1262400Y1024700D03*
X1312000Y954000D03*
X1260000Y993500D03*
X1334500Y1002000D03*
Y1007000D03*
Y992000D03*
Y997000D03*
X1273874Y1423000D03*
X1314375Y1424375D03*
X1327900Y1416500D03*
X1266914Y1394873D03*
X1258187Y1389753D03*
X1281624Y1409209D03*
X1253165Y1384633D03*
X1246949Y1379513D03*
X1263642Y1392313D03*
X1261224Y1387193D03*
X1277624Y1409209D03*
X1250347Y1382073D03*
X1289574Y1483700D03*
X1252674Y1496800D03*
X1266474Y1487500D03*
X1278574Y1488700D03*
X1282374Y1445500D03*
Y1464000D03*
X1296374Y1430700D03*
X1297089Y1450307D03*
X1322000Y1430700D03*
X1284624Y1476400D03*
X1253374Y1470000D03*
X1260574Y1445600D03*
X1256474Y1446000D03*
X1435750Y73750D03*
X1436000Y48500D03*
X1376700Y136000D03*
X1394200Y113700D03*
X1341324Y372244D03*
X1367514Y397100D03*
X1362514D03*
X1424500Y529100D03*
X1436000Y501500D03*
X1345215Y533601D03*
X1383952Y573102D03*
X1341324Y825000D03*
X1367500Y851922D03*
X1362500D03*
X1424400Y982000D03*
X1386900Y1024600D03*
X1383200Y992700D03*
X1436000Y954000D03*
X1347400Y1416200D03*
X1450500Y61000D03*
X1458500Y86500D03*
Y91500D03*
X1501300Y136100D03*
X1447000Y113500D03*
X1442000D03*
X1452000D03*
X1511400Y119500D03*
X1458500Y96500D03*
Y101500D03*
X1465536Y372244D03*
X1492014Y397100D03*
X1487014D03*
X1449500Y504750D03*
X1447000Y566500D03*
X1442000D03*
X1452000D03*
X1450500Y514000D03*
X1458500Y544500D03*
Y539500D03*
Y554500D03*
Y549500D03*
X1511200Y572300D03*
X1465536Y825000D03*
X1493500Y853100D03*
X1487000Y851600D03*
X1443992Y904962D03*
X1450100Y959500D03*
X1447000Y1019000D03*
X1442000D03*
X1452000D03*
X1450500Y966500D03*
X1511400Y1024600D03*
X1506000Y993000D03*
X1458500Y1002000D03*
Y1007000D03*
Y992000D03*
Y997000D03*
X1548279Y69309D03*
X1575400Y50750D03*
X1557500Y35000D03*
X1549000Y76500D03*
X1554000D03*
X1564000D03*
X1559000D03*
X1625300Y136000D03*
X1596400Y135600D03*
Y131100D03*
Y126100D03*
X1616100Y203786D03*
X1589749Y372244D03*
X1611014Y397100D03*
X1616014D03*
X1574000Y504750D03*
X1571500Y566500D03*
X1566500D03*
X1576500D03*
X1548400Y528800D03*
X1575000Y514000D03*
X1560500Y501500D03*
X1583000Y544500D03*
Y539500D03*
Y554500D03*
Y549500D03*
X1591400Y825000D03*
X1616000Y850100D03*
X1611000D03*
X1572900Y902900D03*
X1574000Y957250D03*
X1571500Y1019000D03*
X1566500D03*
X1576500D03*
X1575000Y966500D03*
X1548900Y981500D03*
X1560500Y954000D03*
X1583000Y997000D03*
Y992000D03*
Y1007000D03*
Y1002000D03*
X1699000Y61000D03*
X1672900Y76400D03*
X1684500Y48500D03*
X1692200Y86200D03*
Y91200D03*
X1690400Y114100D03*
X1695400D03*
X1700400D03*
X1635300Y119600D03*
X1692300Y96100D03*
X1707000Y103500D03*
X1712525Y191268D03*
X1709496Y463382D03*
X1717859Y463907D03*
X1714026Y464191D03*
X1711199Y453177D03*
X1708359Y449207D03*
X1706859Y445207D03*
X1698000Y504750D03*
X1695500Y566500D03*
X1690500D03*
X1700500D03*
X1673200Y529000D03*
X1699000Y514000D03*
X1684500Y501500D03*
X1707083Y543435D03*
Y538435D03*
X1706800Y556300D03*
X1706935Y548158D03*
X1634200Y572200D03*
X1713961Y825000D03*
X1709500Y900700D03*
X1698000Y957250D03*
X1695500Y1019000D03*
X1690500D03*
X1700500D03*
X1699000Y966500D03*
X1672800Y981200D03*
X1635100Y1024700D03*
X1631500Y994000D03*
X1684500Y954000D03*
X1707000Y997000D03*
Y992000D03*
Y1007000D03*
Y1002000D03*
X1676511Y1292495D03*
X1651906Y1428973D03*
X1719726Y1402700D03*
X1716026Y1416500D03*
X1663906Y1428973D03*
X1659906D03*
X1656250Y1461250D03*
X1662626Y1464000D03*
Y1445500D03*
X1674926Y1447400D03*
X1676626Y1432000D03*
X1702501Y1434000D03*
X1661626Y1480000D03*
X1799094Y82033D03*
X1811600Y32800D03*
X1794300Y63400D03*
X1796300Y85600D03*
X1806300D03*
X1811300D03*
X1801300D03*
X1803620Y57000D03*
X1807500Y57400D03*
X1749700Y135600D03*
X1759600Y119500D03*
X1805142Y372600D03*
X1723896Y474582D03*
X1753631Y405830D03*
X1735014Y397100D03*
X1740014D03*
X1755159Y469723D03*
X1740906Y465239D03*
X1746859Y465707D03*
X1724096Y464344D03*
X1746959Y459107D03*
X1742758Y456059D03*
X1814500Y566500D03*
X1797400Y528800D03*
X1742859Y484707D03*
X1808500Y501500D03*
X1759750Y587000D03*
X1740000Y850100D03*
X1735000D03*
X1798300Y908900D03*
X1817263Y919025D03*
X1815310Y899557D03*
X1783900Y897700D03*
X1792263Y898225D03*
X1798500Y898662D03*
X1788430Y898509D03*
X1817739Y889758D03*
X1785603Y887495D03*
X1782763Y883525D03*
X1781263Y879525D03*
X1814500Y1019000D03*
X1796900Y981100D03*
X1759300Y1024900D03*
X1808500Y954000D03*
X1756000Y993500D03*
X1735126Y1416300D03*
X1810426Y1476200D03*
X1790226Y1469300D03*
X1800326Y1445800D03*
X1794426Y1446400D03*
X1868600Y68922D03*
X1872900Y49000D03*
X1870607Y75897D03*
X1823300Y88600D03*
X1845900Y77300D03*
X1840900D03*
X1850800Y77200D03*
X1860500Y38100D03*
X1863950Y45400D03*
X1859050Y19000D03*
X1885508Y77413D03*
X1891300Y49400D03*
X1880500Y48900D03*
X1842400Y29500D03*
X1875500Y87000D03*
X1880500D03*
X1865500D03*
X1870500D03*
X1834018Y169783D03*
X1823500Y113500D03*
X1819134Y109132D03*
X1819000Y113500D03*
X1827114Y397900D03*
X1832114D03*
X1836476Y467034D03*
X1822000Y504750D03*
X1848500Y504000D03*
X1819500Y566500D03*
X1824500D03*
X1855750Y540000D03*
X1839750Y530250D03*
X1841500Y558000D03*
X1846000D03*
X1850500D03*
X1823000Y514000D03*
X1883300Y530000D03*
X1853000Y504000D03*
X1870500Y540500D03*
X1865500D03*
X1880500D03*
X1875500D03*
X1831000Y544500D03*
Y539500D03*
Y554500D03*
Y549500D03*
X1838174Y825000D03*
X1859500Y850100D03*
X1864500D03*
X1820700Y940600D03*
X1848500Y940200D03*
X1829563Y904041D03*
X1828763Y865025D03*
X1821263Y900025D03*
X1821363Y893425D03*
X1822000Y957250D03*
X1848500Y957000D03*
X1850500Y1011000D03*
X1846000D03*
X1841500D03*
X1819500Y1019000D03*
X1824500D03*
X1855750Y993000D03*
X1823000Y966500D03*
X1839750Y983000D03*
X1875800Y981000D03*
X1853000Y957000D03*
X1865500Y993000D03*
X1881814Y993136D03*
X1876814D03*
X1871814D03*
X1831000Y1002000D03*
Y1007000D03*
Y992000D03*
Y997000D03*
X1827600Y970700D03*
X1824826Y1470900D03*
X1822326Y1481600D03*
X1919000Y51000D03*
X1922400Y470400D03*
X1923600Y913525D03*
X1914500Y902000D03*
X1918800Y1112100D03*
G54D35*
X862205Y277953D03*
X848032D03*
X833859D03*
X862205Y272441D03*
X848032D03*
X833859D03*
X862205Y263779D03*
X848032D03*
X833859D03*
X862205Y258268D03*
X848032D03*
X833859D03*
X855118Y282677D03*
X840945D03*
X826772D03*
X855118Y277165D03*
X840945D03*
X826772D03*
X855118Y268504D03*
X840945D03*
X826772D03*
X855118Y262992D03*
X840945D03*
X826772D03*
X862205Y306299D03*
X848032D03*
X833859D03*
X862205Y300787D03*
X848032D03*
X833859D03*
X862205Y292126D03*
X848032D03*
X833859D03*
X862205Y286614D03*
X848032D03*
X833859D03*
X855118Y311023D03*
X840945D03*
X826772D03*
X855118Y305512D03*
X840945D03*
X826772D03*
X855118Y296850D03*
X840945D03*
X826772D03*
X855118Y291338D03*
X840945D03*
X826772D03*
X904725Y272835D03*
Y277165D03*
Y282677D03*
X911811Y272441D03*
Y277953D03*
Y282283D03*
X904725Y262992D03*
Y268504D03*
X911811Y253937D03*
Y258268D03*
Y263779D03*
Y268110D03*
X897638Y282283D03*
Y272441D03*
Y277953D03*
Y253937D03*
Y268110D03*
Y258268D03*
Y263779D03*
X890552Y272835D03*
Y277165D03*
Y282677D03*
Y262992D03*
Y268504D03*
X876378Y277953D03*
Y272441D03*
Y263779D03*
Y258268D03*
X869292Y282677D03*
Y277165D03*
Y268504D03*
Y262992D03*
X904725Y305512D03*
Y311023D03*
Y315354D03*
X911811Y306299D03*
Y310630D03*
X904725Y301181D03*
X911811Y300787D03*
X904725Y287008D03*
Y291338D03*
Y296850D03*
X911811Y286614D03*
Y292126D03*
Y296457D03*
X897638Y306299D03*
Y296457D03*
Y286614D03*
Y292126D03*
Y300787D03*
X890552Y305512D03*
Y311023D03*
Y287008D03*
Y301181D03*
Y291338D03*
Y296850D03*
X876378Y306299D03*
Y300787D03*
Y292126D03*
Y286614D03*
X869292Y311023D03*
Y305512D03*
Y296850D03*
Y291338D03*
X1095420Y520057D03*
X1100932D03*
X1109593D03*
X1115105D03*
X1123766D03*
X1129278D03*
X1099357Y527143D03*
X1104869D03*
X1113530D03*
X1119042D03*
X1127703D03*
X1133215D03*
X1095420Y534230D03*
X1100932D03*
X1109593D03*
X1115105D03*
X1123766D03*
X1129278D03*
X1099357Y541317D03*
X1104869D03*
X1113530D03*
X1119042D03*
X1127703D03*
X1133215D03*
X1095420Y548403D03*
X1100932D03*
X1109593D03*
X1115105D03*
X1123766D03*
X1129278D03*
X1099357Y555490D03*
X1104869D03*
X1113530D03*
X1119042D03*
X1127703D03*
X1133215D03*
X1095420Y562576D03*
X1100932D03*
X1109593D03*
X1115105D03*
X1123766D03*
X1129278D03*
X1099357Y569663D03*
X1104869D03*
X1113530D03*
X1119042D03*
X1127703D03*
X1133215D03*
X1095420Y691711D03*
Y705884D03*
Y720057D03*
Y734230D03*
Y748403D03*
Y762577D03*
X1100932Y691711D03*
Y705884D03*
Y720057D03*
Y734230D03*
Y748403D03*
Y762577D03*
X1109593Y691711D03*
Y705884D03*
Y720057D03*
Y734230D03*
Y748403D03*
Y762577D03*
X1115105Y691711D03*
Y705884D03*
Y720057D03*
Y734230D03*
Y748403D03*
Y762577D03*
X1123766Y691711D03*
Y705884D03*
Y720057D03*
Y734230D03*
Y748403D03*
Y762577D03*
X1129278Y691711D03*
Y705884D03*
Y720057D03*
Y734230D03*
Y748403D03*
Y762577D03*
X1099357Y698797D03*
Y712970D03*
Y727144D03*
Y741317D03*
Y755490D03*
X1104869Y698797D03*
Y712970D03*
Y727144D03*
Y741317D03*
Y755490D03*
X1113530Y698797D03*
Y712970D03*
Y727144D03*
Y741317D03*
Y755490D03*
X1119042Y698797D03*
Y712970D03*
Y727144D03*
Y741317D03*
Y755490D03*
X1127703Y698797D03*
Y712970D03*
Y727144D03*
Y741317D03*
Y755490D03*
X1133215Y698797D03*
Y712970D03*
Y727144D03*
Y741317D03*
Y755490D03*
X1095420Y776750D03*
Y790923D03*
Y805096D03*
Y819270D03*
Y833443D03*
Y847616D03*
X1100932Y776750D03*
Y790923D03*
Y805096D03*
Y819270D03*
Y833443D03*
Y847616D03*
X1109593Y776750D03*
Y790923D03*
Y805096D03*
Y819270D03*
Y833443D03*
Y847616D03*
X1115105Y776750D03*
Y790923D03*
Y805096D03*
Y819270D03*
Y833443D03*
Y847616D03*
X1123766Y776750D03*
Y790923D03*
Y805096D03*
Y819270D03*
Y833443D03*
Y847616D03*
X1129278Y776750D03*
Y790923D03*
Y805096D03*
Y819270D03*
Y833443D03*
Y847616D03*
X1099357Y769663D03*
Y783836D03*
Y798010D03*
Y812183D03*
Y826356D03*
Y840529D03*
Y854703D03*
X1104869Y769663D03*
Y783836D03*
Y798010D03*
Y812183D03*
Y826356D03*
Y840529D03*
Y854703D03*
X1113530Y769663D03*
Y783836D03*
Y798010D03*
Y812183D03*
Y826356D03*
Y840529D03*
Y854703D03*
X1119042Y769663D03*
Y783836D03*
Y798010D03*
Y812183D03*
Y826356D03*
Y840529D03*
Y854703D03*
X1127703Y769663D03*
Y783836D03*
Y798010D03*
Y812183D03*
Y826356D03*
Y840529D03*
Y854703D03*
X1133215Y769663D03*
Y783836D03*
Y798010D03*
Y812183D03*
Y826356D03*
Y840529D03*
Y854703D03*
X1095420Y861789D03*
Y875962D03*
Y890136D03*
Y904309D03*
Y918482D03*
Y932655D03*
X1100932Y861789D03*
Y875962D03*
Y890136D03*
Y904309D03*
Y918482D03*
Y932655D03*
X1109593Y861789D03*
Y875962D03*
Y890136D03*
Y904309D03*
Y918482D03*
Y932655D03*
X1115105Y861789D03*
Y875962D03*
Y890136D03*
Y904309D03*
Y918482D03*
Y932655D03*
X1123766Y861789D03*
Y875962D03*
Y890136D03*
Y904309D03*
Y918482D03*
Y932655D03*
X1129278Y861789D03*
Y875962D03*
Y890136D03*
Y904309D03*
Y918482D03*
Y932655D03*
X1099357Y868876D03*
Y883049D03*
Y897222D03*
Y911396D03*
Y925569D03*
Y939742D03*
X1104869Y868876D03*
Y883049D03*
Y897222D03*
Y911396D03*
Y925569D03*
Y939742D03*
X1113530Y868876D03*
Y883049D03*
Y897222D03*
Y911396D03*
Y925569D03*
Y939742D03*
X1119042Y868876D03*
Y883049D03*
Y897222D03*
Y911396D03*
Y925569D03*
Y939742D03*
X1127703Y868876D03*
Y883049D03*
Y897222D03*
Y911396D03*
Y925569D03*
Y939742D03*
X1133215Y868876D03*
Y883049D03*
Y897222D03*
Y911396D03*
Y925569D03*
Y939742D03*
G54D15*
X26300Y873700D03*
Y864100D03*
Y868900D03*
X21500Y873700D03*
Y864100D03*
Y868900D03*
X127600Y437500D03*
Y432700D03*
X122800Y437500D03*
Y432700D03*
X127600Y427900D03*
X122800D03*
X169215Y876085D03*
Y880885D03*
X154215D03*
Y876085D03*
X169215Y895685D03*
Y890885D03*
X154215Y895685D03*
Y890885D03*
X164200Y885700D03*
X158900D03*
X192963Y888625D03*
Y883625D03*
X188163Y888625D03*
X183363D03*
X178563D03*
Y883625D03*
X173763D03*
Y888625D03*
X183363Y883625D03*
X188163D03*
X113363Y884925D03*
X180000Y1424000D03*
Y1430000D03*
X186000Y1424000D03*
Y1430000D03*
X152000Y1377000D03*
Y1383000D03*
X158000Y1377000D03*
Y1383000D03*
X170000D03*
Y1377000D03*
X164000Y1383000D03*
Y1377000D03*
X251200Y457900D03*
Y438300D03*
Y443100D03*
Y453100D03*
X291500Y451100D03*
Y446100D03*
X286700D03*
Y451100D03*
X281900D03*
Y446100D03*
X272300D03*
Y451100D03*
X277100Y446100D03*
Y451100D03*
X267752Y458160D03*
Y438560D03*
Y443360D03*
Y453360D03*
X257127Y448364D03*
X261927D03*
X211590Y427289D03*
X211190Y447189D03*
X197763Y888625D03*
Y883625D03*
X296300Y446100D03*
Y451100D03*
X513917Y1447297D03*
X507917D03*
X519717D03*
X826843Y419764D03*
Y424564D03*
Y429364D03*
X802843Y419664D03*
X807643D03*
X822043Y419764D03*
X802843Y429264D03*
Y424464D03*
X807643D03*
Y429264D03*
X822043Y429364D03*
Y424564D03*
X822400Y587368D03*
Y582568D03*
X817600D03*
Y587368D03*
X803200Y587268D03*
Y582468D03*
X798400D03*
Y587268D03*
X822400Y577768D03*
X817600D03*
X803200Y577668D03*
X798400D03*
X808300Y1227168D03*
Y1222368D03*
X813100D03*
Y1227168D03*
X794100D03*
Y1222368D03*
X789300D03*
Y1227168D03*
X813100Y1217568D03*
X808300D03*
X789300D03*
X794100D03*
X1012000Y371369D03*
X1015537Y365911D03*
X1075627Y374973D03*
X1075829Y380885D03*
X1119877Y423540D03*
Y428340D03*
Y418740D03*
X1124677Y428340D03*
Y423540D03*
Y418740D03*
X1105477Y428240D03*
Y423440D03*
X1100677D03*
Y428240D03*
X1105477Y418640D03*
X1100677D03*
X1076142Y386839D03*
X1057400Y771600D03*
X1057600Y776500D03*
X1067200Y786500D03*
X1062400D03*
Y781500D03*
X1057600Y786500D03*
Y781500D03*
X1067200Y791500D03*
X1062400D03*
X1067200Y796500D03*
X1062400D03*
X1057600D03*
Y791500D03*
X1128500Y1225700D03*
X1133300D03*
X1109400Y1221100D03*
X1114200D03*
Y1225900D03*
X1109400D03*
X1133300Y1220900D03*
X1128500D03*
X1133300Y1216100D03*
X1128500D03*
X1109400Y1216300D03*
X1114200D03*
X1117200Y1346700D03*
X1115000Y1485000D03*
X1118000Y1480500D03*
X1112000D03*
X1151100Y1179300D03*
X1155900D03*
X1151100Y1184100D03*
X1155900D03*
Y1188900D03*
X1151100D03*
X1667359Y434407D03*
Y439207D03*
Y429607D03*
X1662559D03*
Y434407D03*
Y439207D03*
X1814463Y449725D03*
Y454725D03*
X1804900Y451800D03*
X1809915Y461785D03*
Y446985D03*
Y456985D03*
Y442185D03*
X1799600Y451800D03*
X1794915Y461785D03*
Y446985D03*
Y456985D03*
Y442185D03*
X1751774Y430510D03*
X1753959Y450607D03*
X1741159Y873707D03*
X1736359D03*
X1741159Y864107D03*
X1736359D03*
X1741159Y868907D03*
X1736359D03*
X1838463Y454725D03*
Y449725D03*
X1819263D03*
Y454725D03*
X1833663D03*
Y449725D03*
X1828863D03*
Y454725D03*
X1824063D03*
Y449725D03*
X1912663Y888925D03*
Y883925D03*
X1869115Y876385D03*
Y891185D03*
Y881185D03*
Y895985D03*
X1873800Y886300D03*
X1884115Y876385D03*
X1898263Y883925D03*
Y888925D03*
X1903063D03*
Y883925D03*
X1907863D03*
Y888925D03*
X1884115Y891185D03*
Y881185D03*
Y895985D03*
X1893463Y888925D03*
Y883925D03*
X1879100Y886300D03*
X1888663Y888925D03*
Y883925D03*
X1828363Y884925D03*
G54D16*
X90709Y1485118D03*
X70709D03*
X711181D03*
X691181D03*
X1237953D03*
X1217953D03*
X1858425D03*
X1838425D03*
G54D23*
X111024Y188130D03*
Y640886D03*
Y1093642D03*
X235236Y188130D03*
Y640886D03*
Y1093642D03*
X359449Y188130D03*
Y640886D03*
Y1093642D03*
X483661Y188130D03*
Y640886D03*
Y1093642D03*
X607874Y188130D03*
Y640886D03*
Y1093642D03*
X732087Y188130D03*
Y640886D03*
Y1093642D03*
X1281693Y188130D03*
Y640886D03*
Y1093642D03*
X1405906Y188130D03*
Y640886D03*
Y1093642D03*
X1530118Y188130D03*
Y640886D03*
Y1093642D03*
X1654331Y188130D03*
Y640886D03*
Y1093642D03*
X1778543Y188130D03*
Y640886D03*
Y1093642D03*
X1902756Y188130D03*
Y640886D03*
Y1093642D03*
G54D19*
X127988Y71319D03*
Y76319D03*
X134983Y61269D03*
Y56769D03*
X127988Y524075D03*
Y529075D03*
X134983Y514025D03*
Y509525D03*
X127988Y976831D03*
Y981831D03*
X134983Y966781D03*
Y962281D03*
X252200Y71319D03*
Y76319D03*
X259195Y61269D03*
Y56769D03*
X252200Y524075D03*
Y529075D03*
X259195Y514025D03*
Y509525D03*
X252200Y976831D03*
Y981831D03*
X259195Y966781D03*
Y962281D03*
X376413Y71319D03*
Y76319D03*
X383408Y61269D03*
Y56769D03*
X376413Y524075D03*
Y529075D03*
X383408Y514025D03*
Y509525D03*
X376413Y976831D03*
Y981831D03*
X383408Y966781D03*
Y962281D03*
X500625Y71319D03*
Y76319D03*
X507620Y61269D03*
Y56769D03*
X500625Y524075D03*
Y529075D03*
X507620Y514025D03*
Y509525D03*
X500625Y976831D03*
Y981831D03*
X507620Y966781D03*
Y962281D03*
X624838Y71319D03*
Y76319D03*
X631833Y61269D03*
Y56769D03*
X624838Y524075D03*
Y529075D03*
X631833Y514025D03*
Y509525D03*
X624838Y976831D03*
Y981831D03*
X631833Y966781D03*
Y962281D03*
X749051Y71319D03*
Y76319D03*
X756046Y61269D03*
Y56769D03*
X749051Y524075D03*
Y529075D03*
X756046Y514025D03*
Y509525D03*
X749051Y976831D03*
Y981831D03*
X756046Y966781D03*
Y962281D03*
X1275400Y68650D03*
X1270400D03*
X1256750Y53650D03*
X1261250D03*
X1275400Y521406D03*
X1270400D03*
X1256750Y506406D03*
X1261250D03*
X1273975Y976831D03*
Y981831D03*
X1257490Y966361D03*
Y961861D03*
X1399613Y68650D03*
X1394613D03*
X1380963Y53650D03*
X1385463D03*
X1399613Y521406D03*
X1394613D03*
X1380963Y506406D03*
X1385463D03*
X1398188Y976831D03*
Y981831D03*
X1381663Y966381D03*
Y961881D03*
X1523825Y68650D03*
X1518825D03*
X1505175Y53650D03*
X1509675D03*
X1523825Y521406D03*
X1518825D03*
X1505175Y506406D03*
X1509675D03*
X1522400Y976831D03*
Y981831D03*
X1505875Y966321D03*
Y961821D03*
X1648038Y68650D03*
X1643038D03*
X1629388Y53650D03*
X1633888D03*
X1648038Y521406D03*
X1643038D03*
X1629388Y506406D03*
X1633888D03*
X1646613Y976831D03*
Y981831D03*
X1630088Y966881D03*
Y962381D03*
X1772250Y68650D03*
X1767250D03*
X1753600Y53650D03*
X1758100D03*
X1772250Y521406D03*
X1767250D03*
X1753600Y506406D03*
X1758100D03*
X1770825Y976831D03*
Y981831D03*
X1754340Y966361D03*
Y961861D03*
X1896463Y68650D03*
X1891463D03*
X1877813Y53650D03*
X1882313D03*
X1896463Y521406D03*
X1891463D03*
X1877813Y506406D03*
X1882313D03*
X1895038Y976831D03*
Y981831D03*
X1878553Y966361D03*
Y961861D03*
G54D21*
X111024Y39508D03*
Y492264D03*
Y945020D03*
X235236Y39508D03*
Y492264D03*
Y945020D03*
X359449Y39508D03*
Y492264D03*
Y945020D03*
X483661Y39508D03*
Y492264D03*
Y945020D03*
X607874Y39508D03*
Y492264D03*
Y945020D03*
X732087Y39508D03*
Y492264D03*
Y945020D03*
X1281693Y39508D03*
Y492264D03*
Y945020D03*
X1405906Y39508D03*
Y492264D03*
Y945020D03*
X1530118Y39508D03*
Y492264D03*
Y945020D03*
X1654331Y39508D03*
Y492264D03*
Y945020D03*
X1778543Y39508D03*
Y492264D03*
Y945020D03*
X1902756Y39508D03*
Y492264D03*
Y945020D03*
G54D37*
X1002362Y284449D03*
X1014960D03*
X1030709D03*
X1043307D03*
X974015Y261812D03*
X986614D03*
X1002362D03*
X1014960D03*
X1030709D03*
X1043307D03*
X1002362Y278544D03*
X1030709D03*
X974015Y267717D03*
X1002362D03*
X1030709D03*
X974015Y255906D03*
X1002362D03*
X1030709D03*
X1014960Y278544D03*
X1043307D03*
X986614Y267717D03*
X1014960D03*
X1043307D03*
X986614Y255906D03*
X1014960D03*
X1043307D03*
X1002362Y290355D03*
X1030709D03*
X1014960D03*
X1043307D03*
X1101405Y1132638D03*
X1119633D03*
X1108098D03*
X1126326D03*
G54D33*
X233858Y1445275D03*
Y1466929D03*
X614173Y1445275D03*
Y1466929D03*
X1381102Y1445275D03*
Y1466929D03*
X1761417Y1445275D03*
Y1466929D03*
G54D20*
X134983Y65269D03*
Y52769D03*
Y518025D03*
Y505525D03*
Y970781D03*
Y958281D03*
X259195Y65269D03*
Y52769D03*
X203300Y71700D03*
X215100Y62940D03*
X207000Y80500D03*
X259195Y518025D03*
Y505525D03*
Y970781D03*
Y958281D03*
X383408Y65269D03*
Y52769D03*
Y518025D03*
Y505525D03*
Y970781D03*
Y958281D03*
X380780Y1428599D03*
Y1422599D03*
Y1416599D03*
Y1410599D03*
X374780Y1428599D03*
Y1422599D03*
Y1416599D03*
Y1410599D03*
X380780Y1434599D03*
X374780D03*
X454000Y83800D03*
X462100Y62940D03*
X450300Y71700D03*
X507620Y65269D03*
Y52769D03*
Y518025D03*
Y505525D03*
Y970781D03*
Y958281D03*
X542066Y1440238D03*
X537466D03*
X532866D03*
X528798Y1437733D03*
X524722Y1436362D03*
X631833Y65269D03*
Y52769D03*
Y518025D03*
Y505525D03*
Y970781D03*
Y958281D03*
X756046Y65269D03*
Y52769D03*
X704000Y80500D03*
X700300Y71700D03*
X712000Y62940D03*
X756046Y518025D03*
Y505525D03*
Y970781D03*
Y958281D03*
X846950Y645820D03*
Y640820D03*
X859664Y683428D03*
X841309Y796644D03*
X841800Y804499D03*
X786200Y1334100D03*
X794200D03*
X801000Y1333800D03*
X786200Y1326100D03*
X794200D03*
X801000Y1325800D03*
X905100Y777000D03*
X962118Y534117D03*
X1121346Y1315676D03*
Y1319676D03*
X1105100Y1351000D03*
Y1355000D03*
X1099112Y1387273D03*
Y1379273D03*
X1216894Y1318783D03*
Y1314783D03*
X1183894Y1319783D03*
Y1315783D03*
X1236600Y1346763D03*
X1232100D03*
X1217100D03*
X1183894D03*
X1203394D03*
X1198894D03*
X1257490Y970361D03*
Y957861D03*
X1381663Y970381D03*
Y957881D03*
X1505875Y970321D03*
Y957821D03*
X1630088Y970881D03*
Y958381D03*
X1754340Y970361D03*
Y957861D03*
X1884600Y49000D03*
X1878553Y970361D03*
Y957861D03*
G54D11*
X78000Y44000D03*
X38000Y86000D03*
X100412Y6000D03*
X95412D03*
X90412D03*
X85412D03*
X80412D03*
X75412D03*
X70412D03*
X65412D03*
X60412D03*
X55412D03*
X50412D03*
X45412D03*
X40412D03*
X35412D03*
X30412D03*
X25412D03*
X20412D03*
X15412D03*
X10412D03*
X6000Y6588D03*
Y11588D03*
Y16588D03*
Y21588D03*
Y26588D03*
Y31588D03*
Y36588D03*
Y41588D03*
Y46588D03*
Y51588D03*
Y56588D03*
Y61588D03*
Y66588D03*
Y71588D03*
Y76588D03*
Y81588D03*
Y86588D03*
Y91588D03*
X86700Y80700D03*
X92250Y80500D03*
X75000Y73300D03*
X81500Y105000D03*
X48000Y160000D03*
X6000Y96588D03*
Y101588D03*
Y106588D03*
Y111588D03*
Y116588D03*
Y121588D03*
Y126588D03*
Y131588D03*
Y136588D03*
Y141588D03*
Y146588D03*
Y151588D03*
Y156588D03*
Y161588D03*
Y166588D03*
Y171588D03*
Y176588D03*
Y181588D03*
Y186588D03*
X95500Y186000D03*
X89000Y162700D03*
X49500Y140500D03*
X64250Y98500D03*
X73500Y120500D03*
X72900Y133000D03*
X88000Y204000D03*
X76000Y232000D03*
X50000Y200000D03*
X6000Y191588D03*
Y196588D03*
Y201588D03*
Y206588D03*
Y211588D03*
Y216588D03*
Y221588D03*
Y226588D03*
Y231588D03*
Y236588D03*
Y241588D03*
Y246588D03*
Y251588D03*
Y256588D03*
Y261588D03*
Y266588D03*
Y271588D03*
Y276588D03*
Y281588D03*
X38000Y348000D03*
X6000Y286588D03*
Y291588D03*
Y296588D03*
Y301588D03*
Y306588D03*
Y311588D03*
Y316588D03*
Y321588D03*
Y326588D03*
Y331588D03*
Y336588D03*
Y341588D03*
Y346588D03*
Y351588D03*
Y356588D03*
Y361588D03*
Y366588D03*
Y371588D03*
Y376588D03*
X55209Y379278D03*
X38000Y418000D03*
Y452000D03*
X6000Y441588D03*
Y436588D03*
Y431588D03*
Y426588D03*
Y421588D03*
Y416588D03*
Y411588D03*
Y406588D03*
Y386588D03*
Y391588D03*
Y396588D03*
Y401588D03*
Y446588D03*
Y451588D03*
Y456588D03*
Y461588D03*
Y381588D03*
Y466588D03*
Y471588D03*
X65692Y392187D03*
X58728Y393206D03*
X88000Y498000D03*
Y478000D03*
X38000Y544000D03*
X81500Y557500D03*
X6000Y476588D03*
Y481588D03*
Y486588D03*
Y491588D03*
Y496588D03*
Y501588D03*
Y506588D03*
Y511588D03*
Y516588D03*
Y521588D03*
Y526588D03*
Y531588D03*
Y536588D03*
Y541588D03*
Y546588D03*
Y551588D03*
Y556588D03*
Y561588D03*
Y566588D03*
Y571588D03*
X64250Y551000D03*
X86700Y533200D03*
X75000Y525800D03*
X92250Y533000D03*
X40000Y614000D03*
X76000Y642000D03*
X38000Y660000D03*
X6000Y576588D03*
Y581588D03*
Y586588D03*
Y591588D03*
Y596588D03*
Y601588D03*
Y606588D03*
Y611588D03*
Y616588D03*
Y621588D03*
Y626588D03*
Y631588D03*
Y636588D03*
Y641588D03*
Y646588D03*
Y651588D03*
Y656588D03*
Y661588D03*
Y666588D03*
X95500Y638500D03*
X89000Y615200D03*
X73500Y573000D03*
X72800Y585500D03*
X49500Y593000D03*
X92000Y758000D03*
X6000Y671588D03*
Y676588D03*
Y681588D03*
Y686588D03*
Y691588D03*
Y696588D03*
Y701588D03*
Y706588D03*
Y711588D03*
Y716588D03*
Y721588D03*
Y726588D03*
Y731588D03*
Y736588D03*
Y741588D03*
Y746588D03*
Y751588D03*
Y756588D03*
Y761588D03*
X34000Y792000D03*
X100000Y800000D03*
X6000Y766588D03*
Y771588D03*
Y776588D03*
Y781588D03*
Y786588D03*
Y791588D03*
Y796588D03*
Y801588D03*
Y806588D03*
Y811588D03*
Y816588D03*
Y821588D03*
Y826588D03*
Y831588D03*
Y836588D03*
Y841588D03*
Y846588D03*
Y851588D03*
Y856588D03*
X53425Y853600D03*
X46461Y853382D03*
X42942Y831932D03*
X26000Y908000D03*
Y940000D03*
X88000Y946000D03*
X6000Y861588D03*
Y866588D03*
Y871588D03*
Y876588D03*
Y881588D03*
Y886588D03*
Y891588D03*
Y896588D03*
Y901588D03*
Y906588D03*
Y911588D03*
Y916588D03*
Y921588D03*
Y926588D03*
Y931588D03*
Y936588D03*
Y941588D03*
Y946588D03*
Y951588D03*
X81500Y1010500D03*
X38000Y996000D03*
X6000Y956588D03*
Y961588D03*
Y966588D03*
Y971588D03*
Y976588D03*
Y981588D03*
Y986588D03*
Y991588D03*
Y996588D03*
Y1001588D03*
Y1006588D03*
Y1011588D03*
Y1016588D03*
Y1021588D03*
Y1026588D03*
Y1031588D03*
Y1036588D03*
Y1041588D03*
Y1046588D03*
X73500Y1026000D03*
X72600Y1038400D03*
X49500Y1046000D03*
X86700Y986200D03*
X75000Y978800D03*
X64250Y1004000D03*
X92250Y986000D03*
X50000Y1100000D03*
X6000Y1051588D03*
Y1056588D03*
Y1061588D03*
Y1066588D03*
Y1071588D03*
Y1076588D03*
Y1081588D03*
Y1086588D03*
Y1091588D03*
Y1096588D03*
Y1101588D03*
Y1106588D03*
Y1111588D03*
Y1116588D03*
Y1121588D03*
Y1126588D03*
Y1131588D03*
Y1136588D03*
Y1141588D03*
X95500Y1091500D03*
X89000Y1068200D03*
X50000Y1150000D03*
Y1200000D03*
X6000Y1146588D03*
Y1151588D03*
Y1156588D03*
Y1161588D03*
Y1166588D03*
Y1171588D03*
Y1176588D03*
Y1181588D03*
Y1186588D03*
Y1191588D03*
Y1196588D03*
Y1201588D03*
Y1206588D03*
Y1211588D03*
Y1216588D03*
Y1221588D03*
Y1226588D03*
Y1231588D03*
Y1236588D03*
X100000Y1250000D03*
X50000D03*
Y1300000D03*
X100000D03*
X6000Y1321588D03*
Y1326588D03*
Y1331588D03*
Y1286588D03*
Y1291588D03*
Y1296588D03*
Y1301588D03*
Y1306588D03*
Y1311588D03*
Y1316588D03*
Y1241588D03*
Y1246588D03*
Y1251588D03*
Y1256588D03*
Y1261588D03*
Y1266588D03*
Y1271588D03*
Y1276588D03*
Y1281588D03*
X50000Y1350000D03*
X100000D03*
Y1400000D03*
X50000D03*
X6000Y1421588D03*
Y1416588D03*
Y1411588D03*
Y1406588D03*
Y1401588D03*
Y1396588D03*
Y1391588D03*
Y1386588D03*
Y1381588D03*
Y1376588D03*
Y1371588D03*
Y1366588D03*
Y1361588D03*
Y1356588D03*
Y1351588D03*
Y1346588D03*
Y1341588D03*
Y1426588D03*
Y1336588D03*
X86000Y1444000D03*
X6000Y1451588D03*
Y1446588D03*
Y1441588D03*
Y1436588D03*
Y1431588D03*
X99000Y1501000D03*
X61500Y1502000D03*
X87539Y1499118D03*
X82539D03*
X77539D03*
X72539D03*
X67539D03*
X92539D03*
X11000Y1455500D03*
X15500Y1458500D03*
X17811Y1462693D03*
Y1467693D03*
Y1472693D03*
Y1477693D03*
Y1482693D03*
Y1487693D03*
Y1492693D03*
Y1497693D03*
Y1502693D03*
Y1507693D03*
X17500Y1512000D03*
X21819Y1513685D03*
X26819D03*
X31819D03*
X36819D03*
X41819D03*
X46819D03*
X51819D03*
X56819D03*
X58500Y1508000D03*
X144000Y88000D03*
X195412Y6000D03*
X190412D03*
X185412D03*
X180412D03*
X175412D03*
X170412D03*
X165412D03*
X160412D03*
X155412D03*
X150412D03*
X145412D03*
X140412D03*
X135412D03*
X130412D03*
X125412D03*
X120412D03*
X115412D03*
X110412D03*
X105412D03*
X111437Y81319D03*
Y66319D03*
X106937Y84370D03*
Y93819D03*
X111437Y51319D03*
X118437Y27697D03*
X157900Y17900D03*
X157600Y24500D03*
X157400Y35800D03*
X158000Y152000D03*
X154000Y106000D03*
X111437Y161319D03*
Y151319D03*
X173500Y140500D03*
X111437Y131319D03*
Y121319D03*
X127600Y119300D03*
X106937Y103268D03*
X174000Y236000D03*
X118437Y199941D03*
X112000Y316000D03*
X162000Y310000D03*
X150000Y350000D03*
X189342Y378932D03*
X102000Y440000D03*
X174000Y410000D03*
X192861Y400482D03*
X156000Y544000D03*
X130000Y560000D03*
X144000Y550000D03*
X152000Y492000D03*
X160000Y508000D03*
X188250Y550951D03*
X106937Y556024D03*
Y537126D03*
Y546575D03*
X111437Y534075D03*
Y519075D03*
Y504075D03*
X118437Y480453D03*
X180500Y576000D03*
X162000Y614000D03*
X118437Y652697D03*
X111437Y614075D03*
Y604075D03*
Y584075D03*
Y574075D03*
X173500Y593000D03*
X140750Y575500D03*
X174000Y686000D03*
X156000Y768000D03*
X150000Y800000D03*
X176425Y853700D03*
X176558Y831000D03*
X172318Y844782D03*
X136000Y912000D03*
X140000Y938000D03*
X188000Y932000D03*
X118437Y933209D03*
X173763Y907525D03*
X189763D03*
X185763D03*
X181763D03*
X177763D03*
X193763D03*
X180500Y1028500D03*
X160000Y982000D03*
X142000Y1008000D03*
X140750Y1028500D03*
X174000Y1046000D03*
X111437Y1036831D03*
Y1026831D03*
X188750Y1004000D03*
X111437Y956831D03*
Y986831D03*
Y971831D03*
X106937Y1008780D03*
Y989882D03*
Y999331D03*
X136500Y1111500D03*
X164000Y1068000D03*
X118437Y1105453D03*
X111437Y1066831D03*
Y1056831D03*
X158484Y1416000D03*
X139774Y1420600D03*
X131143Y1427661D03*
X102000Y1505500D03*
X177433Y1513685D03*
X182433D03*
X187433D03*
X192433D03*
X147433D03*
X152433D03*
X157433D03*
X162433D03*
X167433D03*
X172433D03*
X103000Y1511000D03*
X107433Y1513685D03*
X112433D03*
X117433D03*
X122433D03*
X127433D03*
X132433D03*
X137433D03*
X157574Y1453500D03*
X145374Y1452500D03*
X145274Y1434685D03*
X156674Y1435085D03*
X167499Y1434000D03*
X104074Y1462500D03*
X114874Y1476700D03*
X118574Y1465900D03*
X121274Y1447400D03*
X142433Y1513685D03*
X262000Y30000D03*
X280000Y90000D03*
X264000Y94000D03*
X290412Y6000D03*
X285412D03*
X280412D03*
X275412D03*
X270412D03*
X265412D03*
X260412D03*
X255412D03*
X250412D03*
X245412D03*
X240412D03*
X235412D03*
X230412D03*
X225412D03*
X220412D03*
X215412D03*
X210412D03*
X205412D03*
X200412D03*
X231000Y82000D03*
X231149Y93819D03*
X235649Y81319D03*
Y66319D03*
Y51319D03*
X242649Y27697D03*
X284000Y160000D03*
X256000Y142000D03*
X235649Y161319D03*
Y151319D03*
X219500Y186000D03*
X213500Y162700D03*
X235649Y131319D03*
Y121319D03*
X231149Y103268D03*
X250900Y119500D03*
X197000Y133000D03*
X197500Y120500D03*
X198000Y198000D03*
X212000Y236000D03*
X288000Y242000D03*
X250000Y250000D03*
X242649Y199941D03*
X214000Y328000D03*
X250000Y350000D03*
Y300000D03*
X291042Y379232D03*
X286000Y422000D03*
X199825Y400700D03*
X271590Y469789D03*
X275590D03*
X279590D03*
X283590D03*
X287590D03*
X291590D03*
X212500Y557500D03*
X216000Y498000D03*
X286000Y490000D03*
Y506000D03*
X268000Y544000D03*
X278000Y554000D03*
X231149Y556024D03*
X232433Y537126D03*
X231149Y546575D03*
X235649Y534075D03*
Y519075D03*
Y504075D03*
X242649Y480453D03*
X210700Y533200D03*
X199000Y525800D03*
X216250Y533000D03*
X286000Y612000D03*
X200000Y646000D03*
X242649Y652697D03*
X235649Y614075D03*
X213500Y615200D03*
X219500Y638500D03*
X235649Y604075D03*
Y584075D03*
Y574075D03*
X268187Y578998D03*
X197200Y585500D03*
X197500Y573000D03*
X250000Y700000D03*
Y750000D03*
Y850000D03*
Y800000D03*
X291042Y831932D03*
X252000Y906000D03*
X212000Y916000D03*
X213500Y951500D03*
X263500Y939500D03*
X242649Y933209D03*
X284500Y982000D03*
X265000Y1008500D03*
X206000Y1010500D03*
X198000Y1026000D03*
X197300Y1038500D03*
X264250Y1028500D03*
X235649Y1036831D03*
Y1026831D03*
X252100Y959100D03*
X211200Y986200D03*
X199500Y978800D03*
X216750Y986000D03*
X231149Y1008780D03*
Y989882D03*
Y999331D03*
X235649Y986831D03*
Y971831D03*
X288000Y1068000D03*
X200000Y1100000D03*
X242649Y1105453D03*
X220000Y1091500D03*
X213500Y1068200D03*
X235649Y1066831D03*
Y1056831D03*
X200000Y1200000D03*
X250000D03*
Y1150000D03*
X200000D03*
X227500Y1303000D03*
X250000Y1350000D03*
X233074Y1429500D03*
X239274Y1429600D03*
X237235Y1419039D03*
X236974Y1425000D03*
X259500Y1494000D03*
X256000Y1466000D03*
X283000Y1492000D03*
X279000Y1498500D03*
X197433Y1513685D03*
X202433D03*
X207433D03*
X212433D03*
X217433D03*
X222433D03*
X227433D03*
X232433D03*
X237433D03*
X242433D03*
X247433D03*
X252433D03*
X257433D03*
X262433D03*
X267433D03*
X272433D03*
X277433D03*
X278646Y1509398D03*
Y1504398D03*
X288685Y1490063D03*
X386000Y28000D03*
X338000Y30000D03*
Y44000D03*
X385412Y6000D03*
X380412D03*
X375412D03*
X370412D03*
X365412D03*
X360412D03*
X355412D03*
X350412D03*
X345412D03*
X340412D03*
X335412D03*
X330412D03*
X325412D03*
X320412D03*
X315412D03*
X310412D03*
X305412D03*
X300412D03*
X295412D03*
X355362Y84370D03*
Y93819D03*
X359862Y81319D03*
Y66319D03*
X323500Y73300D03*
X340750Y80500D03*
X335200Y80700D03*
X359862Y51319D03*
X366862Y27697D03*
X359862Y161319D03*
Y151319D03*
X344000Y186000D03*
X337500Y162700D03*
X298000Y140500D03*
X359862Y131319D03*
X357506Y123493D03*
X355362Y103268D03*
X375500Y119400D03*
X312750Y98500D03*
X322000Y120500D03*
X321500Y133000D03*
X324000Y196000D03*
X366862Y199941D03*
X358000Y318000D03*
X320000Y422000D03*
X336000Y466000D03*
X384000Y468000D03*
X301525Y400900D03*
X294561Y400682D03*
X338000Y498000D03*
X355362Y556024D03*
Y537126D03*
Y546575D03*
X312750Y551000D03*
X359862Y534075D03*
Y519075D03*
Y504075D03*
X366862Y480453D03*
X335200Y533200D03*
X323500Y525800D03*
X340750Y533000D03*
X324000Y650000D03*
X359862Y614075D03*
X366862Y652697D03*
X344000Y638500D03*
X337500Y615200D03*
X359862Y604075D03*
Y584075D03*
X374261Y572963D03*
X322000Y573000D03*
X323380Y589452D03*
X298000Y593000D03*
X334000Y686000D03*
X342000Y758000D03*
X350000Y850000D03*
Y800000D03*
X301525Y853600D03*
X294561Y853382D03*
X337500Y946500D03*
X359500Y925400D03*
X330000Y1010500D03*
X304500Y1028500D03*
X359862Y1036831D03*
Y1026831D03*
X322000Y1026000D03*
X321200Y1038500D03*
X298000Y1046000D03*
X358800Y955900D03*
X355362Y1008780D03*
Y989882D03*
Y999331D03*
X359862Y986831D03*
Y971831D03*
X335200Y986200D03*
X323500Y978800D03*
X312750Y1004000D03*
X340750Y986000D03*
X318000Y1058000D03*
X326000Y1106000D03*
X366862Y1105453D03*
X359862Y1066831D03*
Y1056831D03*
X344000Y1091500D03*
X337500Y1068200D03*
X300000Y1200000D03*
Y1150000D03*
X384055Y1330472D03*
Y1320472D03*
X354055Y1330472D03*
X364055D03*
X354055Y1320472D03*
X364055D03*
X324055Y1330472D03*
X334055D03*
X324055Y1320472D03*
X334055D03*
X304055Y1330472D03*
Y1320472D03*
X294055Y1330472D03*
Y1320472D03*
X384055Y1340472D03*
Y1350472D03*
X354055Y1340472D03*
Y1350472D03*
X364055Y1340472D03*
Y1350472D03*
X324055Y1340472D03*
Y1350472D03*
X334055Y1340472D03*
Y1350472D03*
X304055D03*
Y1340472D03*
X294055Y1350472D03*
Y1340472D03*
X350000Y1400000D03*
X323688Y1357736D03*
X328688D03*
X333688D03*
X338688D03*
X343688D03*
X348688D03*
X353688D03*
X358688D03*
X363688D03*
X368688D03*
X373688D03*
X378688D03*
X383688D03*
X298688D03*
X303688D03*
X308688D03*
X313688D03*
X318688D03*
X293688D03*
X300000Y1400000D03*
X293685Y1490063D03*
X298685D03*
X303685D03*
X308685D03*
X313685D03*
X318685D03*
X323685D03*
X328685D03*
X333685D03*
X338685D03*
X343685D03*
X348685D03*
X353685D03*
X358685D03*
X363685D03*
X368685D03*
X373685D03*
X378685D03*
X383685D03*
X410679Y31098D03*
X414000Y58000D03*
X402000Y64000D03*
X480412Y6000D03*
X475412D03*
X470412D03*
X465412D03*
X460412D03*
X455412D03*
X450412D03*
X445412D03*
X440412D03*
X435412D03*
X430412D03*
X425412D03*
X420412D03*
X415412D03*
X410412D03*
X405412D03*
X400412D03*
X395412D03*
X390412D03*
X479574Y84370D03*
Y93819D03*
X467500Y116000D03*
X394000Y164000D03*
Y174000D03*
X462000Y162700D03*
X468000Y186000D03*
X422000Y140500D03*
X479574Y103268D03*
X441300Y126000D03*
X445500Y133000D03*
X440849Y111648D03*
X388000Y196000D03*
X416000D03*
X400000Y350000D03*
X415542Y378932D03*
X428000Y430000D03*
X460000Y468000D03*
X426025Y400700D03*
X419061Y400382D03*
X402000Y560000D03*
X388000Y548000D03*
X410000Y544000D03*
X392000Y490000D03*
X460000Y496000D03*
X479574Y556024D03*
Y537126D03*
Y546575D03*
X436750Y551000D03*
X459200Y533200D03*
X446993Y527868D03*
X464750Y533000D03*
X410000Y616000D03*
X468000Y638500D03*
X467029Y610775D03*
X441641Y574141D03*
X445546Y586021D03*
X421820Y593641D03*
X389250Y575500D03*
X422000Y684000D03*
X454000Y686000D03*
X466000Y762000D03*
X400000Y800000D03*
X425725Y853400D03*
X418761Y853082D03*
X415242Y831882D03*
X387500Y939000D03*
X462000Y947000D03*
X428500Y1028500D03*
X454000Y1010500D03*
X407000Y984000D03*
X389500Y1009000D03*
X446000Y1026000D03*
X445100Y1038500D03*
X389250Y1028500D03*
X422000Y1046000D03*
X459200Y986200D03*
X447500Y978800D03*
X436750Y1004000D03*
X464750Y986000D03*
X479574Y1008780D03*
Y989882D03*
Y999331D03*
X448000Y1106000D03*
X410000Y1068000D03*
X468000Y1091500D03*
X462000Y1068200D03*
X450000Y1150000D03*
Y1200000D03*
X474055Y1330472D03*
X484055D03*
X474055Y1320472D03*
X484055D03*
X444055Y1330472D03*
X454055D03*
X444055Y1320472D03*
X454055D03*
X414055Y1330472D03*
X424055D03*
X414055Y1320472D03*
X424055D03*
X394055Y1330472D03*
Y1320472D03*
X474055Y1340472D03*
Y1350472D03*
X484055Y1340472D03*
Y1350472D03*
X444055Y1340472D03*
Y1350472D03*
X454055Y1340472D03*
Y1350472D03*
X414055Y1340472D03*
Y1350472D03*
X424055Y1340472D03*
Y1350472D03*
X394055Y1340472D03*
Y1350472D03*
X390500Y1386000D03*
X388688Y1357736D03*
X393688D03*
X462000Y1382985D03*
Y1372985D03*
Y1362985D03*
X474000Y1382985D03*
Y1372985D03*
Y1362985D03*
X426000D03*
X450000Y1372985D03*
Y1382985D03*
X414000Y1372985D03*
X450000Y1362985D03*
X438000Y1372985D03*
X414000Y1362985D03*
X438000D03*
X426000Y1372985D03*
X438000Y1382985D03*
X414000D03*
X426000D03*
X388685Y1490063D03*
X393685D03*
X398685D03*
X403685D03*
X408685D03*
X413685D03*
X418685D03*
X423685D03*
X428685D03*
X433685D03*
X438685D03*
X443685D03*
X448685D03*
X453685D03*
X458685D03*
X463685D03*
X468685D03*
X473685D03*
X478685D03*
X532000Y90000D03*
X534000Y58000D03*
X512000Y28000D03*
X575412Y6000D03*
X570412D03*
X565412D03*
X560412D03*
X555412D03*
X550412D03*
X545412D03*
X540412D03*
X535412D03*
X530412D03*
X525412D03*
X520412D03*
X515412D03*
X510412D03*
X505412D03*
X500412D03*
X495412D03*
X490412D03*
X485412D03*
X572000Y73300D03*
X484074Y81319D03*
Y66319D03*
Y51319D03*
X491074Y27697D03*
X556000Y156000D03*
X568000Y190000D03*
X544000Y160000D03*
X502500Y139500D03*
X512000Y104000D03*
X546500Y140500D03*
X484074Y161319D03*
Y151319D03*
X561250Y98500D03*
X570500Y120500D03*
X569900Y133000D03*
X499900Y119400D03*
X484074Y131319D03*
Y121319D03*
X534000Y222500D03*
X493000Y218500D03*
X491074Y199941D03*
X539742Y379232D03*
X543242Y400682D03*
X550225Y400900D03*
X516000Y488000D03*
X574000D03*
X524000Y560000D03*
X561250Y551000D03*
X572000Y525800D03*
X484074Y504075D03*
X491074Y480453D03*
X483513Y535912D03*
X484074Y519075D03*
X536000Y644000D03*
X510000Y656000D03*
X491074Y652697D03*
X484074Y614075D03*
X565279Y578552D03*
X569900Y585500D03*
X551276Y597925D03*
X483265Y606243D03*
X484074Y584075D03*
Y574075D03*
X513250Y574252D03*
X552000Y686000D03*
X542000Y764000D03*
X500000Y800000D03*
Y850000D03*
X512000Y939000D03*
X483549Y925564D03*
X513500Y1009000D03*
X532000Y983000D03*
X553000Y1028500D03*
X570500Y1026000D03*
X569900Y1038500D03*
X546500Y1046000D03*
X513250Y1028500D03*
X484074Y1036831D03*
Y1026831D03*
X572000Y978800D03*
X561250Y1004000D03*
X499800Y956831D03*
X484074Y986831D03*
Y971831D03*
X534000Y1068000D03*
X550000Y1100000D03*
X491074Y1105453D03*
X484074Y1066831D03*
Y1056831D03*
X500000Y1150000D03*
X550000D03*
Y1200000D03*
X500000D03*
X522000Y1294000D03*
X498000Y1332985D03*
X510000Y1344485D03*
X498000Y1352985D03*
X522000Y1344485D03*
X498000Y1342985D03*
X510000Y1354485D03*
X522000D03*
X510000Y1364485D03*
X522000D03*
X510000Y1374485D03*
Y1384485D03*
X522000Y1374485D03*
Y1384485D03*
X498000Y1382985D03*
Y1372985D03*
X486000Y1382985D03*
Y1372985D03*
X498000Y1362985D03*
X486000D03*
X501000Y1494000D03*
X503000Y1499000D03*
X494500Y1490500D03*
X574937Y1513685D03*
X569937D03*
X564937D03*
X559937D03*
X554937D03*
X549937D03*
X544937D03*
X539937D03*
X534937D03*
X529937D03*
X524937D03*
X483685Y1490063D03*
X488685D03*
X503244Y1504378D03*
Y1509378D03*
X504937Y1513685D03*
X509937D03*
X514937D03*
X528500Y1444600D03*
X519937Y1513685D03*
X500000Y1472000D03*
X507250Y1478000D03*
X585500Y45000D03*
X650000Y84000D03*
X578000Y52000D03*
X592500Y28000D03*
X670412Y6000D03*
X665412D03*
X660412D03*
X655412D03*
X650412D03*
X645412D03*
X640412D03*
X635412D03*
X630412D03*
X625412D03*
X620412D03*
X615412D03*
X610412D03*
X605412D03*
X600412D03*
X595412D03*
X590412D03*
X585412D03*
X580412D03*
X603787Y84370D03*
Y93819D03*
X608287Y81319D03*
Y66319D03*
X589250Y80500D03*
X583700Y80700D03*
X608287Y51319D03*
X615287Y27697D03*
X638000Y104000D03*
X654000Y162500D03*
X664500Y97000D03*
X579000Y105000D03*
X670500Y140500D03*
X608287Y161319D03*
Y151319D03*
X592500Y186000D03*
X586000Y162700D03*
X608287Y131319D03*
Y121319D03*
X603787Y103268D03*
X624000Y119400D03*
X626000Y140000D03*
X652000Y214000D03*
X582500Y266000D03*
X615287Y199941D03*
X586500Y292000D03*
X643000Y317500D03*
X614500Y318500D03*
X639000Y354500D03*
X602500Y365000D03*
X650742Y378932D03*
X661225Y400738D03*
X654261Y400382D03*
X638000Y488000D03*
X644000Y558000D03*
X603787Y556024D03*
Y537126D03*
Y546575D03*
X608287Y534075D03*
Y519075D03*
Y504075D03*
X615287Y480453D03*
X589250Y533000D03*
X583700Y533200D03*
X671000Y648000D03*
X672500Y615500D03*
X615287Y652697D03*
X622687Y614091D03*
X592500Y638500D03*
X586043Y615962D03*
X670500Y593000D03*
X622703Y604103D03*
X623005Y584047D03*
X608287Y574075D03*
X637750Y575500D03*
X590000Y680000D03*
X600000Y770000D03*
X650000D03*
X624000Y846000D03*
X579148Y832411D03*
X666625Y853400D03*
X589805Y854600D03*
X659661Y853082D03*
X582667Y853605D03*
X656142Y831632D03*
X585000Y948000D03*
X636000Y939000D03*
X615287Y933209D03*
X578000Y1010500D03*
X652500Y984500D03*
X625000Y1014500D03*
X653500Y997500D03*
X670500Y1046000D03*
X637750Y1028500D03*
X608287Y1036831D03*
Y1026831D03*
X601800Y955500D03*
X589250Y986000D03*
X603787Y1008780D03*
Y989882D03*
Y999331D03*
X608287Y986831D03*
Y971831D03*
X583700Y986200D03*
X599000Y1115500D03*
X631500Y1112500D03*
X660000Y1068000D03*
X615287Y1105453D03*
X592500Y1091500D03*
X608287Y1066831D03*
Y1056831D03*
X586000Y1068200D03*
X672000Y1146000D03*
X670000Y1196000D03*
X668000Y1418900D03*
X672000Y1419000D03*
X581800Y1376500D03*
Y1384400D03*
Y1392300D03*
Y1360700D03*
Y1368600D03*
Y1352800D03*
Y1344900D03*
X589700Y1392300D03*
Y1400200D03*
Y1344900D03*
Y1352800D03*
Y1384400D03*
Y1376500D03*
Y1368600D03*
Y1360700D03*
X597600Y1400200D03*
Y1408100D03*
Y1360700D03*
Y1368600D03*
Y1392300D03*
Y1376500D03*
Y1384400D03*
Y1352800D03*
Y1344900D03*
X629200D03*
X621300D03*
X613400D03*
X605500D03*
Y1360700D03*
X613400D03*
X621300D03*
X629200D03*
X605500Y1352800D03*
X613400D03*
X621300D03*
X629200D03*
Y1368600D03*
Y1376500D03*
X605500Y1408100D03*
Y1400200D03*
Y1392300D03*
Y1384400D03*
Y1376500D03*
Y1368600D03*
X613400Y1400200D03*
Y1392300D03*
Y1384400D03*
Y1376500D03*
Y1368600D03*
X621300Y1376500D03*
Y1368600D03*
X613400Y1408100D03*
X658000Y1449200D03*
X669937Y1513685D03*
X659937D03*
X654937D03*
X649937D03*
X644937D03*
X639937D03*
X634937D03*
X629937D03*
X624937D03*
X619937D03*
X614937D03*
X609937D03*
X604937D03*
X599937D03*
X594937D03*
X589937D03*
X584937D03*
X579937D03*
X664937D03*
X765412Y6000D03*
X760412D03*
X755412D03*
X750412D03*
X745412D03*
X740412D03*
X735412D03*
X730412D03*
X725412D03*
X720412D03*
X715412D03*
X710412D03*
X705412D03*
X700412D03*
X695412D03*
X690412D03*
X685412D03*
X680412D03*
X675412D03*
X729201Y87285D03*
X727636Y93834D03*
X732500Y81319D03*
Y66319D03*
Y51319D03*
X739500Y27697D03*
X681000Y171500D03*
X732500Y161319D03*
Y151319D03*
X716500Y186000D03*
X710300Y162700D03*
X747290Y118820D03*
X732500Y131319D03*
Y121319D03*
X728000Y103268D03*
X694500Y120500D03*
X694200Y133000D03*
X714000Y240000D03*
X700000Y200000D03*
X732087Y207847D03*
X756000Y326000D03*
X718000Y332000D03*
X704500Y408500D03*
X716000Y568500D03*
X688000Y496000D03*
X728000Y556024D03*
Y537126D03*
Y546575D03*
X688298Y551625D03*
X732500Y504075D03*
X707700Y533200D03*
X696000Y525800D03*
X732500Y519075D03*
X713250Y533000D03*
X732500Y534075D03*
X724600Y487100D03*
X747843Y612115D03*
X739500Y652697D03*
X710300Y635400D03*
Y615200D03*
X748200Y572200D03*
X732500Y574075D03*
X694200Y585500D03*
X732500Y584075D03*
X694500Y573000D03*
X746356Y604075D03*
X710000Y760500D03*
X726500Y681500D03*
X693500Y680000D03*
X712000Y720000D03*
X710000Y950500D03*
X739500Y933209D03*
X677000Y1028500D03*
X702500Y1010500D03*
X753050Y1028500D03*
X694500Y1026000D03*
X694000Y1038500D03*
X732500Y1036831D03*
Y1026831D03*
X730900Y955800D03*
X707700Y986200D03*
X696000Y978800D03*
X685250Y1004000D03*
X713250Y986000D03*
X728000Y1008780D03*
Y989882D03*
Y999331D03*
X732500Y986831D03*
Y971831D03*
X750000Y1084000D03*
X698000Y1102000D03*
X739500Y1105453D03*
X716500Y1091500D03*
X710300Y1068200D03*
X732500Y1066831D03*
Y1056831D03*
X738000Y1152000D03*
X740000Y1202000D03*
X748000Y1170000D03*
X746000Y1218000D03*
X700000Y1150000D03*
X768867Y1311110D03*
Y1335110D03*
Y1327110D03*
Y1319110D03*
X698500Y1418900D03*
X693000Y1418800D03*
X689000Y1419000D03*
X681000Y1419100D03*
X685000Y1418900D03*
X703500Y1426000D03*
X676500Y1419500D03*
X768867Y1383110D03*
Y1359110D03*
Y1367110D03*
Y1351110D03*
Y1343110D03*
Y1391110D03*
Y1399110D03*
Y1375110D03*
X720455Y1438500D03*
X684000Y1482000D03*
X699500Y1476000D03*
X685000Y1453500D03*
X690000Y1448500D03*
X695000Y1453500D03*
X690000Y1458500D03*
Y1453500D03*
X722000Y1503500D03*
X718500Y1500000D03*
X680500Y1503500D03*
X674937Y1513685D03*
X688012Y1499118D03*
X693012D03*
X698012D03*
X703012D03*
X708012D03*
X713012D03*
X724000Y1509500D03*
X725551Y1513685D03*
X730551D03*
X735551D03*
X740551D03*
X745551D03*
X750551D03*
X755551D03*
X760551D03*
X765551D03*
X746832Y1451034D03*
X735232Y1439334D03*
X739332Y1462234D03*
X750867Y1438001D03*
X722200Y1476900D03*
X678500Y1510500D03*
X777465Y93947D03*
Y88947D03*
Y83947D03*
Y78947D03*
Y73947D03*
Y68947D03*
Y63947D03*
Y58947D03*
Y53947D03*
Y48947D03*
Y43947D03*
Y38947D03*
Y33947D03*
Y28947D03*
Y23947D03*
Y18947D03*
Y13947D03*
X778000Y9500D03*
X775412Y6000D03*
X770412D03*
X777465Y183947D03*
Y178947D03*
Y173947D03*
Y168947D03*
Y163947D03*
Y158947D03*
Y153947D03*
Y148947D03*
Y143947D03*
Y138947D03*
Y133947D03*
Y128947D03*
Y123947D03*
Y118947D03*
Y113947D03*
Y108947D03*
Y103947D03*
Y98947D03*
X862205Y282283D03*
X848032D03*
X833859D03*
X862205Y268110D03*
X848032D03*
X833859D03*
X862205Y253937D03*
X848032D03*
X833859D03*
X855118Y272835D03*
X840945D03*
X826772D03*
X771500Y251000D03*
X802000Y263500D03*
X809500Y197500D03*
X805522Y195764D03*
X808961Y201678D03*
Y206678D03*
Y211678D03*
Y216678D03*
Y236678D03*
Y231678D03*
Y226678D03*
Y221678D03*
Y241678D03*
X779022Y190764D03*
X784022Y194764D03*
X800522Y195764D03*
X795522D03*
X790522D03*
X862205Y310630D03*
X848032D03*
X833859D03*
X862205Y296457D03*
X848032D03*
X833859D03*
X855118Y315354D03*
X840945D03*
X826772D03*
X855118Y301181D03*
X840945D03*
X826772D03*
X855118Y287008D03*
X840945D03*
X826772D03*
X804500Y379000D03*
X769500Y431500D03*
X807500Y473700D03*
X834000Y499000D03*
X822841Y662242D03*
X839400Y744920D03*
X833300Y856920D03*
X854973Y780437D03*
X810700Y776500D03*
X818162Y819005D03*
X810659Y767500D03*
X818434Y919985D03*
X820883Y879428D03*
X820900Y888500D03*
X826000Y1004000D03*
X846500Y997500D03*
X827000Y985500D03*
X822470Y981470D03*
X826000Y1062000D03*
X846500Y1055000D03*
X826000Y1094000D03*
Y1128000D03*
X844000Y1092000D03*
Y1128000D03*
X859113Y1283983D03*
X776867Y1311110D03*
Y1335110D03*
Y1327110D03*
Y1319110D03*
X775600Y1302400D03*
X790056Y1297863D03*
X798056D03*
X782056D03*
X860000Y1410843D03*
X842500Y1411343D03*
X776867Y1399110D03*
X790330Y1407929D03*
X782330D03*
X798330D03*
X795000Y1377900D03*
X786600Y1378100D03*
X790950Y1372703D03*
X776867Y1383110D03*
Y1359110D03*
X782950Y1372703D03*
X776867Y1367110D03*
Y1375110D03*
X798950Y1372703D03*
X776867Y1391110D03*
X790223Y1339930D03*
X782223Y1339430D03*
X798223Y1339930D03*
X776867Y1351110D03*
Y1343110D03*
X820000Y1448000D03*
X779500Y1491000D03*
X775000Y1495500D03*
X770551Y1513685D03*
X773528Y1510662D03*
Y1505662D03*
Y1500662D03*
X786803Y1490063D03*
X791803D03*
X796803D03*
X801803D03*
X806803D03*
X811803D03*
X816803D03*
X821803D03*
X826803D03*
X831803D03*
X836803D03*
X841803D03*
X846803D03*
X851803D03*
X856803D03*
X861803D03*
X876378Y282283D03*
Y268110D03*
Y253937D03*
X869292Y272835D03*
X887127Y254031D03*
X897638Y310630D03*
X890552Y315354D03*
X876378Y310630D03*
Y296457D03*
X869292Y315354D03*
Y301181D03*
Y287008D03*
X874858Y757002D03*
X918400Y760750D03*
X915580Y857420D03*
X942500Y797867D03*
X874500Y774500D03*
X879205Y873548D03*
X918369Y923258D03*
X914208Y924279D03*
X883072Y886211D03*
X889458Y907846D03*
X877877Y891277D03*
X940750Y886000D03*
X928250Y885250D03*
X934500Y885156D03*
X948298Y1215500D03*
X943500Y1233000D03*
X951500D03*
X959500D03*
X957000Y1207500D03*
X953100Y1211400D03*
X953000Y1203600D03*
X904000Y1191700D03*
X877400D03*
X928500Y1220700D03*
X884056Y1283981D03*
X871556D03*
X888000Y1424000D03*
X926000Y1420000D03*
X876500Y1410843D03*
X888776Y1402228D03*
X901435Y1402196D03*
X945200Y1398300D03*
Y1393500D03*
X950200Y1394500D03*
X866500Y1392892D03*
X913935Y1402196D03*
X866000Y1452000D03*
X900000Y1450000D03*
X866803Y1490063D03*
X871803D03*
X876803D03*
X881803D03*
X886803D03*
X891803D03*
X896803D03*
X901803D03*
X906803D03*
X911803D03*
X916803D03*
X921803D03*
X926803D03*
X931803D03*
X936803D03*
X941803D03*
X946803D03*
X951803D03*
X956803D03*
X1033046Y379981D03*
X1035000Y370500D03*
X1032924Y374988D03*
X965700Y519617D03*
X968200Y547200D03*
X964200Y855600D03*
X1009600Y851054D03*
X986471Y829716D03*
X1009950Y838000D03*
X1025636Y854819D03*
X1012125Y925875D03*
X1025251Y893000D03*
X1025065Y896965D03*
X1028500Y879500D03*
X1014807Y899075D03*
X1015007Y895000D03*
X974120Y858920D03*
X976242Y884600D03*
X980442Y882900D03*
X993942D03*
X1013231Y1089300D03*
X1001687Y1111499D03*
X1020000Y1230000D03*
X971700Y1193100D03*
X963500Y1233000D03*
X967500D03*
X960900Y1211400D03*
Y1203600D03*
X1022818Y1393489D03*
X1024193Y1422899D03*
X1010943Y1413899D03*
X1005943Y1406700D03*
X975443Y1407700D03*
X992443Y1406700D03*
X1000443D03*
X988443D03*
X996443Y1406800D03*
X983943Y1407399D03*
X979443Y1406999D03*
X997000Y1496000D03*
X993000Y1491500D03*
X961803Y1490063D03*
X966803D03*
X971803D03*
X976803D03*
X981803D03*
X986803D03*
X998126Y1503614D03*
Y1508614D03*
Y1513614D03*
X1003126D03*
X1008126D03*
X1013126D03*
X1018126D03*
X1023126D03*
X1028126D03*
X1033126D03*
X1038126D03*
X1043126D03*
X1048126D03*
X1053126D03*
X1027288Y1467441D03*
X1034100Y1500564D03*
X1024175Y1482189D03*
X1002118Y1471365D03*
X998325Y1471434D03*
X992443Y1441399D03*
X1002443D03*
X997443Y1436399D03*
Y1446399D03*
Y1441399D03*
X965443Y1436399D03*
X1089000Y217500D03*
X1150000Y250000D03*
X1100000D03*
X1068734Y195764D03*
X1064500Y197500D03*
X1065055Y201895D03*
Y206895D03*
Y211895D03*
Y216895D03*
X1148734Y195764D03*
X1143734D03*
X1138734D03*
X1133734D03*
X1128734D03*
X1123734D03*
X1118734D03*
X1113734D03*
X1103734D03*
X1098734D03*
X1093734D03*
X1088734D03*
X1083734D03*
X1078734D03*
X1073734D03*
X1098000Y378000D03*
X1136000D03*
X1100000Y350000D03*
Y300000D03*
X1150000D03*
X1144000Y418000D03*
X1093000Y502000D03*
X1137600Y527100D03*
X1137446Y541317D03*
Y555490D03*
Y569663D03*
X1083000Y620000D03*
X1095000D03*
X1112298Y618498D03*
X1137446Y698798D03*
Y712971D03*
Y727144D03*
Y741317D03*
Y755490D03*
Y769663D03*
Y783836D03*
Y798010D03*
Y812183D03*
Y826356D03*
Y840529D03*
Y854703D03*
Y868876D03*
Y883049D03*
Y897222D03*
Y911396D03*
Y925569D03*
Y939742D03*
X1130000Y994000D03*
X1106000D03*
X1138000Y970000D03*
X1084000Y1092000D03*
X1130000Y1154000D03*
X1078000Y1166000D03*
X1080000Y1230000D03*
X1100625Y1292025D03*
X1107000Y1323500D03*
X1114000Y1430000D03*
X1087933Y1411323D03*
X1082933D03*
X1077933D03*
X1095567Y1426057D03*
X1058126Y1513614D03*
X1061675Y1510352D03*
X1065210Y1506817D03*
X1066638Y1472408D03*
Y1467408D03*
Y1462408D03*
Y1457408D03*
Y1452408D03*
Y1447408D03*
Y1442408D03*
X1095567Y1431057D03*
Y1436057D03*
Y1441057D03*
Y1446057D03*
Y1451057D03*
Y1456057D03*
Y1461057D03*
Y1466057D03*
X1096039Y1505861D03*
X1099575Y1509397D03*
X1103110Y1512932D03*
X1107798Y1513685D03*
X1112798D03*
X1117798D03*
X1122798D03*
X1127798D03*
X1132798D03*
X1137798D03*
X1142798D03*
X1147798D03*
X1095567Y1471057D03*
X1066638Y1502408D03*
X1234500Y6000D03*
X1243844D03*
X1238844D03*
X1230409Y7565D03*
Y12565D03*
Y17565D03*
Y22565D03*
Y27565D03*
Y32565D03*
Y37565D03*
Y42565D03*
Y47565D03*
Y52565D03*
Y57565D03*
Y62565D03*
Y67565D03*
Y72565D03*
Y77565D03*
Y82565D03*
Y87565D03*
Y92565D03*
X1238000Y164000D03*
X1230409Y97565D03*
Y102565D03*
Y107565D03*
Y112565D03*
Y117565D03*
Y122565D03*
Y127565D03*
Y132565D03*
Y137565D03*
Y142565D03*
Y147565D03*
Y152565D03*
Y157565D03*
Y162565D03*
Y167565D03*
Y172565D03*
Y177565D03*
Y182565D03*
X1236500Y216000D03*
X1200000Y250000D03*
X1218734Y195764D03*
X1213734D03*
X1208734D03*
X1203734D03*
X1198734D03*
X1193734D03*
X1188734D03*
X1183734D03*
X1178734D03*
X1173734D03*
X1168734D03*
X1163734D03*
X1158734D03*
X1153734D03*
X1218000Y344000D03*
X1225600Y368700D03*
X1200000Y300000D03*
X1190000Y466000D03*
X1184000Y440000D03*
X1206000Y430500D03*
X1169000Y511500D03*
X1188000Y753500D03*
X1180000Y832000D03*
Y848000D03*
X1217089Y846182D03*
X1224088Y844900D03*
X1213611Y831932D03*
X1200337Y912300D03*
X1200407Y918060D03*
X1240000Y1070000D03*
X1176000D03*
X1200000Y1100000D03*
X1178000Y1214000D03*
X1200000Y1200000D03*
Y1150000D03*
X1196000Y1366000D03*
X1212000D03*
X1242000Y1412000D03*
X1226000Y1436000D03*
X1238000Y1444000D03*
X1190000Y1494000D03*
X1156000D03*
X1200000Y1450000D03*
X1245500Y1500500D03*
X1208000Y1502500D03*
X1234783Y1499118D03*
X1229783D03*
X1224783D03*
X1219783D03*
X1214783D03*
X1239783D03*
X1152798Y1513685D03*
X1157798D03*
X1162798D03*
X1167798D03*
X1172798D03*
X1177798D03*
X1182798D03*
X1187798D03*
X1192798D03*
X1197798D03*
X1202798D03*
X1205500Y1509000D03*
X1279400Y68650D03*
X1266400D03*
X1326000Y92000D03*
X1338844Y6000D03*
X1333844D03*
X1328844D03*
X1323844D03*
X1318844D03*
X1313844D03*
X1308844D03*
X1303844D03*
X1298844D03*
X1293844D03*
X1288844D03*
X1283844D03*
X1278844D03*
X1273844D03*
X1268844D03*
X1263844D03*
X1258844D03*
X1253844D03*
X1248844D03*
X1298655Y59926D03*
X1282106Y81319D03*
Y66319D03*
X1299800Y56000D03*
X1278038Y93821D03*
X1278698Y84340D03*
X1307200Y45000D03*
X1289106Y27697D03*
X1282106Y51319D03*
X1303500Y35000D03*
X1262000Y174000D03*
X1313000Y185500D03*
X1314000Y150500D03*
X1282106Y161319D03*
Y151319D03*
X1302500Y152000D03*
X1305000Y185500D03*
X1298500D03*
X1282106Y131319D03*
Y121319D03*
X1266600Y119500D03*
X1262468Y103268D03*
X1272500Y213000D03*
X1307500Y205000D03*
X1338000Y225000D03*
X1289106Y199941D03*
X1252000Y358000D03*
X1294500Y331500D03*
X1278500Y313000D03*
X1259445Y379019D03*
X1337824Y379176D03*
X1317500Y435500D03*
X1316000Y419000D03*
X1269926Y400687D03*
X1262964Y400469D03*
X1281693Y473218D03*
X1279400Y521406D03*
X1266400D03*
X1298500Y562500D03*
X1317500Y533500D03*
X1277606Y546575D03*
Y556024D03*
Y537126D03*
X1307500Y501500D03*
X1299900Y534200D03*
X1311200Y511500D03*
X1282106Y519075D03*
Y534075D03*
Y504075D03*
X1303800Y522500D03*
X1327000Y487000D03*
X1318000Y660000D03*
X1332000Y646000D03*
X1312973Y643128D03*
X1282106Y614075D03*
X1273979Y652690D03*
X1305000Y638500D03*
X1298000Y638300D03*
X1314000Y603500D03*
X1282106Y574075D03*
Y604075D03*
Y584075D03*
X1302500Y605000D03*
X1272211Y575575D03*
X1254000Y748000D03*
X1312000Y812000D03*
X1278000Y810000D03*
X1250000Y820000D03*
X1337824Y832935D03*
X1310000Y860000D03*
X1270000Y868000D03*
X1274000Y933209D03*
X1298000Y1014000D03*
X1318000Y986000D03*
X1266000Y1046000D03*
X1252000Y1010000D03*
X1266400Y1024700D03*
X1282106Y1036831D03*
Y1026831D03*
X1300600Y986800D03*
X1307500Y954000D03*
X1311200Y964000D03*
X1282106Y956831D03*
X1303800Y975000D03*
X1277606Y1008780D03*
Y999331D03*
Y989882D03*
X1282106Y986831D03*
Y971831D03*
X1266000Y1128000D03*
X1264000Y1082000D03*
X1250000Y1100000D03*
X1289106Y1105453D03*
X1314000Y1056000D03*
X1313000Y1091000D03*
X1298500D03*
X1302500Y1057500D03*
X1305000Y1091000D03*
X1282106Y1066831D03*
Y1056831D03*
X1250000Y1200000D03*
Y1150000D03*
X1288000Y1296000D03*
X1274000Y1314000D03*
X1300000Y1388000D03*
X1274000Y1374000D03*
X1318540Y1424331D03*
X1249000Y1504500D03*
X1328464Y1513685D03*
X1333464D03*
X1338464D03*
X1293464D03*
X1298464D03*
X1303464D03*
X1308464D03*
X1313464D03*
X1318464D03*
X1323464D03*
X1250500Y1510500D03*
X1253464Y1513685D03*
X1258464D03*
X1263464D03*
X1268464D03*
X1273464D03*
X1278464D03*
X1283464D03*
X1306625Y1434000D03*
X1303874Y1453750D03*
X1292374Y1452500D03*
X1301534Y1431345D03*
X1289124Y1430700D03*
X1253374Y1459300D03*
X1260874Y1481400D03*
X1264774Y1470700D03*
X1266574Y1452300D03*
X1288464Y1513685D03*
X1403613Y68650D03*
X1390613D03*
X1432000Y30000D03*
X1358000Y91000D03*
X1433844Y6000D03*
X1428844D03*
X1423844D03*
X1418844D03*
X1413844D03*
X1408844D03*
X1403844D03*
X1398844D03*
X1393844D03*
X1388844D03*
X1383844D03*
X1378844D03*
X1373844D03*
X1368844D03*
X1363844D03*
X1358844D03*
X1353844D03*
X1348844D03*
X1343844D03*
X1406319Y66319D03*
Y81319D03*
X1401819Y93819D03*
Y84370D03*
X1435200Y58500D03*
X1427800Y69500D03*
X1406319Y51319D03*
X1413319Y27697D03*
X1431500Y48500D03*
X1392500Y173000D03*
X1389000Y148500D03*
X1422000Y98000D03*
X1346000Y179000D03*
X1351500Y144500D03*
X1406319Y151319D03*
Y161319D03*
X1426500Y152000D03*
X1422500Y185500D03*
X1429000D03*
X1406319Y121319D03*
Y131319D03*
X1401819Y103268D03*
X1391200Y119500D03*
X1428000Y238000D03*
X1388500Y230000D03*
X1394000Y249000D03*
X1397937Y199951D03*
X1373000Y234500D03*
X1388000Y378000D03*
X1400000Y350000D03*
X1378000Y430000D03*
X1376000Y414000D03*
X1436500Y430000D03*
X1341343Y400626D03*
X1348305Y400844D03*
X1403613Y521406D03*
X1390613D03*
X1384000Y554000D03*
X1352000Y516000D03*
X1432000Y482000D03*
X1364000Y492000D03*
X1401819Y546575D03*
Y556024D03*
Y537126D03*
X1406319Y534075D03*
Y519075D03*
Y504075D03*
X1413319Y480453D03*
X1424400Y534200D03*
X1431500Y501500D03*
X1435200Y511500D03*
X1427800Y522500D03*
X1382000Y592000D03*
X1384000Y646000D03*
X1358000Y600000D03*
X1413319Y652697D03*
X1406319Y614075D03*
X1422500Y638500D03*
X1429000D03*
X1406319Y604075D03*
Y584075D03*
Y574075D03*
X1394110Y575530D03*
X1426500Y605000D03*
X1430000Y752000D03*
X1346000Y704000D03*
X1382000Y688000D03*
X1384000Y782000D03*
X1400000Y850000D03*
X1348305Y853600D03*
X1341343Y853382D03*
X1413319Y933209D03*
X1342000Y976000D03*
X1356000Y998000D03*
X1424100Y987000D03*
X1391000Y1024800D03*
X1406319Y1036831D03*
Y1026831D03*
Y956831D03*
X1431500Y954000D03*
X1435200Y964000D03*
X1427800Y975000D03*
X1401819Y1008780D03*
Y999331D03*
Y989882D03*
X1406319Y986831D03*
Y971831D03*
X1360000Y1054000D03*
X1350000Y1100000D03*
X1413319Y1105453D03*
X1426500Y1057500D03*
X1422500Y1091000D03*
X1429000D03*
X1406319Y1066831D03*
Y1056831D03*
X1350000Y1150000D03*
X1400000D03*
Y1200000D03*
X1350000D03*
X1366000Y1388000D03*
X1385474Y1429500D03*
X1380074D03*
X1383374Y1425000D03*
X1383674Y1419000D03*
X1406000Y1444000D03*
X1433500Y1490500D03*
X1428500Y1494000D03*
X1403500Y1513500D03*
X1398500D03*
X1363464Y1513685D03*
X1368464D03*
X1373464D03*
X1378464D03*
X1383464D03*
X1388464D03*
X1393464D03*
X1353464D03*
X1358464D03*
X1343464D03*
X1348464D03*
X1408464D03*
X1413464D03*
X1418464D03*
X1423464D03*
X1425890Y1510111D03*
Y1505111D03*
Y1500111D03*
X1527825Y68650D03*
X1514825D03*
X1474000Y78000D03*
X1508000Y36000D03*
X1468000Y42000D03*
X1482000Y66000D03*
X1528844Y6000D03*
X1523844D03*
X1518844D03*
X1513844D03*
X1508844D03*
X1503844D03*
X1498844D03*
X1493844D03*
X1488844D03*
X1483844D03*
X1478844D03*
X1473844D03*
X1468844D03*
X1463844D03*
X1458844D03*
X1453844D03*
X1448844D03*
X1443844D03*
X1438844D03*
X1530531Y66319D03*
Y81319D03*
X1526031Y93819D03*
Y84370D03*
X1439500Y81000D03*
X1530531Y51319D03*
X1508500Y102500D03*
X1441100Y130800D03*
X1494000Y98000D03*
X1484000Y158000D03*
X1530531Y151319D03*
X1526823Y161308D03*
X1437000Y185500D03*
X1438000Y150500D03*
X1530531Y121319D03*
Y131319D03*
X1526031Y103268D03*
X1515400Y119400D03*
X1523100Y193700D03*
X1502000Y196000D03*
X1457500Y289000D03*
X1508500Y292500D03*
X1450000Y350000D03*
X1462036Y379176D03*
X1484000Y432000D03*
X1465555Y400626D03*
X1472517Y400844D03*
X1527825Y521406D03*
X1514825D03*
X1442500Y532000D03*
X1480000Y546000D03*
X1510000Y488000D03*
X1476000Y518000D03*
X1526031Y546575D03*
Y556024D03*
Y537126D03*
X1530531Y534075D03*
Y519075D03*
Y504075D03*
X1451800Y583800D03*
X1498000Y586000D03*
X1490000Y598000D03*
X1500000Y640000D03*
X1460000Y646000D03*
X1530531Y614075D03*
X1437000Y638500D03*
X1530531Y604075D03*
Y584075D03*
Y574075D03*
X1515200Y572200D03*
X1438000Y603500D03*
X1508000Y748000D03*
X1472517Y853600D03*
X1465555Y853382D03*
X1462036Y831932D03*
X1442500Y984500D03*
X1478000Y976000D03*
X1480000Y1020000D03*
X1515400Y1025000D03*
X1530531Y1036831D03*
Y1026831D03*
Y956831D03*
X1526031Y1008780D03*
Y999331D03*
Y989882D03*
X1530531Y986831D03*
Y971831D03*
X1500000Y1100000D03*
X1530531Y1066831D03*
Y1056831D03*
X1437000Y1091000D03*
X1438000Y1056000D03*
X1450000Y1150000D03*
X1500000D03*
Y1200000D03*
X1450000D03*
X1500000Y1300000D03*
X1450000D03*
Y1350000D03*
X1500000D03*
Y1450000D03*
X1450000D03*
X1439716Y1490063D03*
X1444716D03*
X1449716D03*
X1454716D03*
X1459716D03*
X1464716D03*
X1469716D03*
X1474716D03*
X1479716D03*
X1484716D03*
X1489716D03*
X1494716D03*
X1499716D03*
X1504716D03*
X1509716D03*
X1514716D03*
X1519716D03*
X1524716D03*
X1529716D03*
X1594000Y56000D03*
X1574000Y26000D03*
X1608000Y62000D03*
Y50000D03*
X1623844Y6000D03*
X1618844D03*
X1613844D03*
X1608844D03*
X1603844D03*
X1598844D03*
X1593844D03*
X1588844D03*
X1583844D03*
X1578844D03*
X1573844D03*
X1568844D03*
X1563844D03*
X1558844D03*
X1553844D03*
X1548844D03*
X1543844D03*
X1538844D03*
X1533844D03*
X1549300Y56000D03*
X1548500Y62900D03*
X1553000Y35000D03*
X1556700Y45000D03*
X1537531Y27697D03*
X1593500Y160500D03*
X1546000Y112000D03*
X1547000Y156222D03*
Y185500D03*
X1562500Y150500D03*
X1561500Y185500D03*
X1553500Y189500D03*
X1598000Y206000D03*
X1568000Y204000D03*
X1592000Y236000D03*
X1550000Y350000D03*
X1586249Y379176D03*
X1553500Y431500D03*
X1604000Y432500D03*
X1596730Y400844D03*
X1589768Y400626D03*
X1566500Y533000D03*
X1604000Y536000D03*
X1594000Y506000D03*
X1558000Y482000D03*
X1559700Y511500D03*
X1556000Y501500D03*
X1548600Y534900D03*
X1552300Y522500D03*
X1537531Y480453D03*
X1570100Y583800D03*
X1568000Y660000D03*
X1584000Y648000D03*
X1553500Y638500D03*
X1561500Y639860D03*
X1537500Y656000D03*
X1551000Y605000D03*
X1562500Y603500D03*
X1602000Y684000D03*
X1566000Y772000D03*
X1550000Y850000D03*
X1596730Y853600D03*
X1589768Y853382D03*
X1586249Y831932D03*
X1599000Y941000D03*
X1579000Y940000D03*
X1564000Y876000D03*
X1537531Y933209D03*
X1604000Y1022000D03*
X1544000Y1004500D03*
X1566500Y985500D03*
X1600500Y975000D03*
X1612000Y980000D03*
X1548900Y987600D03*
X1556000Y954000D03*
X1559700Y964000D03*
X1552300Y975000D03*
X1561500Y1091000D03*
X1553500D03*
X1600000Y1100000D03*
X1537531Y1105453D03*
X1551000Y1057500D03*
X1547000Y1091000D03*
X1562500Y1056000D03*
X1600000Y1200000D03*
Y1150000D03*
X1550000Y1300000D03*
X1600000D03*
X1550000Y1350000D03*
X1600000D03*
Y1450000D03*
X1550000D03*
X1534716Y1490063D03*
X1539716D03*
X1544716D03*
X1549716D03*
X1554716D03*
X1559716D03*
X1564716D03*
X1569716D03*
X1574716D03*
X1579716D03*
X1584716D03*
X1589716D03*
X1594716D03*
X1599716D03*
X1604716D03*
X1609716D03*
X1614716D03*
X1619716D03*
X1624716D03*
X1652038Y68650D03*
X1639038D03*
X1718000Y66000D03*
X1680000Y26000D03*
X1632000D03*
X1718844Y6000D03*
X1713844D03*
X1708844D03*
X1703844D03*
X1698844D03*
X1693844D03*
X1688844D03*
X1683844D03*
X1678844D03*
X1673844D03*
X1668844D03*
X1663844D03*
X1658844D03*
X1653844D03*
X1648844D03*
X1643844D03*
X1638844D03*
X1633844D03*
X1628844D03*
X1676300Y69500D03*
X1683700Y58500D03*
X1686730Y80991D03*
X1654744Y66319D03*
Y81319D03*
X1650244Y93819D03*
Y84370D03*
X1680000Y48500D03*
X1654744Y51319D03*
X1661744Y27697D03*
X1636000Y176000D03*
X1677500Y185500D03*
X1686500Y150500D03*
X1675000Y152000D03*
X1654744Y151319D03*
Y161319D03*
X1685500Y185500D03*
X1654744Y121319D03*
X1653206Y134559D03*
X1650244Y103268D03*
X1639300Y119500D03*
X1648000Y212000D03*
X1682000Y206000D03*
X1661744Y199941D03*
X1671003Y190635D03*
X1650000Y380000D03*
X1638500Y311500D03*
X1715000Y305500D03*
X1648000Y468000D03*
X1714000Y391000D03*
X1652038Y521406D03*
X1639038D03*
X1682000Y484000D03*
X1720000Y506000D03*
X1650244Y546575D03*
Y556024D03*
Y537126D03*
X1654744Y534075D03*
Y519075D03*
Y504075D03*
X1661744Y480453D03*
X1680000Y501500D03*
X1673200Y535100D03*
X1683700Y511500D03*
X1676300Y522500D03*
X1706000Y646000D03*
X1632000Y648000D03*
X1634000Y618000D03*
X1661744Y652697D03*
X1654744Y614075D03*
X1671000Y638500D03*
X1685500D03*
X1677500D03*
X1654744Y604075D03*
Y584075D03*
X1652808Y574040D03*
X1686500Y603500D03*
X1675000Y605000D03*
X1638200Y572200D03*
X1700000Y700000D03*
X1650000D03*
Y750000D03*
X1700000D03*
X1650000Y850000D03*
X1720942Y853600D03*
X1713980Y853382D03*
X1710461Y831932D03*
X1690200Y937700D03*
X1718000Y938000D03*
X1716000Y878000D03*
X1661800Y933400D03*
X1668000Y1004000D03*
X1690500Y986000D03*
X1672800Y987300D03*
X1639100Y1024900D03*
X1654744Y1036831D03*
Y1026831D03*
Y956831D03*
X1676300Y975000D03*
X1683700Y964000D03*
X1680000Y954000D03*
X1650244Y1008780D03*
Y999331D03*
Y989882D03*
X1654744Y986831D03*
Y971831D03*
X1638000Y1082000D03*
X1696000Y1106000D03*
X1661744Y1105453D03*
X1677500Y1091000D03*
X1686500Y1056000D03*
X1671000Y1091000D03*
X1675000Y1057500D03*
X1685500Y1091000D03*
X1654744Y1066831D03*
Y1056831D03*
X1650000Y1150000D03*
X1700000D03*
Y1200000D03*
X1650000D03*
Y1300000D03*
X1674000Y1410000D03*
X1650000Y1350000D03*
X1669376Y1429200D03*
X1649500Y1497500D03*
X1646000Y1492000D03*
X1720968Y1513685D03*
X1715968D03*
X1710968D03*
X1705968D03*
X1700968D03*
X1695968D03*
X1690968D03*
X1685968D03*
X1680968D03*
X1670968D03*
X1675968D03*
X1629716Y1490063D03*
X1634716D03*
X1639716D03*
X1650488Y1504165D03*
Y1509165D03*
X1650968Y1513685D03*
X1655968D03*
X1660968D03*
X1665968D03*
X1694751Y1434000D03*
X1683926Y1453750D03*
X1672626Y1452500D03*
X1686226Y1432500D03*
X1776250Y68650D03*
X1763250D03*
X1756000Y25500D03*
X1730000Y58000D03*
X1813844Y6000D03*
X1808844D03*
X1803844D03*
X1798844D03*
X1793844D03*
X1788844D03*
X1783844D03*
X1778844D03*
X1773844D03*
X1768844D03*
X1763844D03*
X1758844D03*
X1753844D03*
X1748844D03*
X1743844D03*
X1738844D03*
X1733844D03*
X1728844D03*
X1723844D03*
X1778956Y66319D03*
Y81319D03*
X1774456Y93819D03*
Y84370D03*
X1785956Y27697D03*
X1778956Y51319D03*
X1730500Y177500D03*
X1730000Y136000D03*
X1746000Y106000D03*
X1809500Y185500D03*
X1801500D03*
X1811305Y147994D03*
X1799000Y152000D03*
X1795000Y185500D03*
X1778956Y151319D03*
Y161319D03*
Y121319D03*
Y131319D03*
X1774456Y103268D03*
X1763600Y119400D03*
X1804000Y205000D03*
X1724000Y232000D03*
X1754000Y234000D03*
X1750000Y200000D03*
X1785956Y199941D03*
X1768000Y310000D03*
X1781500Y366000D03*
X1801642Y379532D03*
X1724000Y422000D03*
X1745737Y400643D03*
X1759904Y400647D03*
X1812123Y401200D03*
X1805142Y400982D03*
X1814359Y473207D03*
X1749952Y405830D03*
X1776250Y521406D03*
X1763250D03*
X1813700Y548300D03*
X1796000Y566500D03*
X1728000Y554000D03*
X1757200Y558900D03*
X1730000Y568000D03*
X1774456Y556024D03*
X1767342Y533721D03*
X1774456Y546575D03*
X1785956Y480453D03*
X1804000Y501500D03*
X1807700Y511500D03*
X1800300Y522500D03*
X1798100Y537973D03*
X1785728Y538736D03*
X1778956Y519075D03*
Y504075D03*
X1818000Y656000D03*
X1762000Y628000D03*
X1756000Y646000D03*
X1785956Y652697D03*
X1795000Y638500D03*
X1801500D03*
X1809500D03*
X1778956Y614075D03*
X1810500Y603500D03*
X1799000Y605000D03*
X1778956Y604075D03*
Y584075D03*
Y574075D03*
X1759750Y576000D03*
X1758000Y748000D03*
X1756000Y684000D03*
X1808000Y848000D03*
X1760000Y846000D03*
X1800000Y800000D03*
X1778500Y917500D03*
X1738000Y904000D03*
X1785956Y933209D03*
X1794500Y1007000D03*
X1814500Y985500D03*
X1724000Y974000D03*
X1728000Y1002000D03*
X1796900Y987200D03*
X1763300Y1024800D03*
X1778956Y1036831D03*
Y1026831D03*
X1800300Y975000D03*
X1804000Y954000D03*
X1807700Y964000D03*
X1778956Y956831D03*
X1774456Y1008780D03*
Y999331D03*
Y989882D03*
X1778956Y986831D03*
Y971831D03*
X1730000Y1050000D03*
X1762000Y1080000D03*
X1785956Y1105453D03*
X1809500Y1091000D03*
X1801500D03*
X1810500Y1056000D03*
X1795000Y1091000D03*
X1799000Y1057500D03*
X1778956Y1066831D03*
Y1056831D03*
X1750000Y1150000D03*
Y1200000D03*
X1800000Y1300000D03*
Y1250000D03*
X1760000Y1394000D03*
X1800000Y1350000D03*
X1766526Y1429400D03*
X1760326Y1429500D03*
X1763926Y1419000D03*
X1763626Y1425000D03*
X1786004Y1513500D03*
X1780968Y1513685D03*
X1775968D03*
X1770968D03*
X1765968D03*
X1760968D03*
X1755968D03*
X1750968D03*
X1745968D03*
X1740968D03*
X1796004Y1513500D03*
X1801004D03*
X1806004D03*
X1811004D03*
X1816004D03*
X1730968Y1513685D03*
X1725968D03*
X1791004Y1513500D03*
X1735968Y1513685D03*
X1790226Y1458600D03*
X1803426Y1452600D03*
X1804326Y1480500D03*
X1794226Y1473300D03*
X1900463Y68650D03*
X1887463D03*
X1913844Y6000D03*
X1908844D03*
X1903844D03*
X1898844D03*
X1893844D03*
X1888844D03*
X1883844D03*
X1878844D03*
X1873844D03*
X1868844D03*
X1863844D03*
X1858844D03*
X1853844D03*
X1848844D03*
X1843844D03*
X1838844D03*
X1833844D03*
X1828844D03*
X1823844D03*
X1818844D03*
X1898669Y93819D03*
Y84370D03*
X1903169Y66319D03*
Y81319D03*
Y51319D03*
X1910169Y27697D03*
X1887900Y41300D03*
X1878000Y29300D03*
X1821850Y35400D03*
X1824200Y23400D03*
Y19000D03*
X1851500Y171500D03*
X1867600Y104300D03*
X1903169Y151319D03*
Y161319D03*
X1881000Y162200D03*
X1883000Y181500D03*
X1841000Y140000D03*
X1903169Y121319D03*
Y131319D03*
X1898669Y103268D03*
X1860817Y120141D03*
X1864800Y132500D03*
X1840500Y237500D03*
X1850000Y200000D03*
X1900000Y250000D03*
X1910169Y199941D03*
X1829500Y311000D03*
X1900000Y300000D03*
Y350000D03*
X1830000Y424000D03*
X1838000Y415500D03*
X1850000Y400000D03*
X1900000D03*
Y450000D03*
X1818359Y473207D03*
X1822359D03*
X1826359D03*
X1830359D03*
X1834359D03*
X1900463Y521406D03*
X1887463D03*
X1884000Y488000D03*
X1854000Y482000D03*
X1875000Y558000D03*
X1898669Y546575D03*
Y556024D03*
Y537126D03*
X1855750Y551000D03*
X1903169Y534075D03*
Y519075D03*
Y504075D03*
X1910169Y480453D03*
X1851400Y623800D03*
X1850000Y650000D03*
X1910169Y652697D03*
X1903169Y614075D03*
X1880500Y615200D03*
X1887000Y638500D03*
X1903169Y604075D03*
Y584075D03*
Y574075D03*
X1865000Y573000D03*
X1864700Y585500D03*
X1841000Y593000D03*
X1846000Y686000D03*
X1900000Y750000D03*
Y700000D03*
Y800000D03*
X1845155Y853600D03*
X1838193Y853382D03*
X1834674Y831932D03*
X1910169Y933209D03*
X1888763Y907525D03*
X1892763D03*
X1896763D03*
X1900763D03*
X1904763D03*
X1908763D03*
X1872500Y1010500D03*
X1826000Y1036500D03*
X1864500Y1038500D03*
X1865000Y1026000D03*
X1903169Y1036831D03*
Y1026831D03*
X1841000Y1046000D03*
X1903169Y956831D03*
X1898669Y1008780D03*
Y999331D03*
Y989882D03*
X1903169Y986831D03*
Y971831D03*
X1855750Y1004000D03*
X1850000Y1078000D03*
X1910169Y1105453D03*
X1887000Y1091500D03*
X1880500Y1068200D03*
X1903169Y1066831D03*
Y1056831D03*
X1850000Y1200000D03*
X1900000D03*
Y1150000D03*
X1850000D03*
X1900000Y1300000D03*
X1850000D03*
X1900000Y1250000D03*
X1850000D03*
X1900000Y1400000D03*
X1850000D03*
Y1350000D03*
X1900000D03*
X1904000Y1504000D03*
X1878000Y1484000D03*
X1822000Y1444000D03*
X1900000Y1450000D03*
X1869500Y1503500D03*
X1865500Y1500000D03*
X1829500Y1501500D03*
X1826500Y1506500D03*
X1855256Y1499118D03*
X1850256D03*
X1845256D03*
X1840256D03*
X1826040Y1513315D03*
X1821040D03*
X1835256Y1499118D03*
X1860256D03*
X1871157Y1509110D03*
X1871582Y1513685D03*
X1876582D03*
X1881582D03*
X1886582D03*
X1891582D03*
X1896582D03*
X1901582D03*
X1906582D03*
X1911582D03*
X1928843Y8985D03*
Y93985D03*
Y88985D03*
Y83985D03*
Y78985D03*
Y73985D03*
Y68985D03*
Y63985D03*
Y58985D03*
Y53985D03*
Y48985D03*
Y43985D03*
Y38985D03*
Y28985D03*
Y23985D03*
Y18985D03*
Y13985D03*
Y33985D03*
X1923844Y6000D03*
X1918844D03*
X1928843Y98985D03*
Y188985D03*
Y183985D03*
Y178985D03*
Y173985D03*
Y168985D03*
Y163985D03*
Y158985D03*
Y153985D03*
Y148985D03*
Y143985D03*
Y138985D03*
Y133985D03*
Y128985D03*
Y123985D03*
Y118985D03*
Y113985D03*
Y108985D03*
Y103985D03*
Y283985D03*
Y278985D03*
Y273985D03*
Y268985D03*
Y263985D03*
Y258985D03*
Y253985D03*
Y248985D03*
Y243985D03*
Y238985D03*
Y233985D03*
Y228985D03*
Y223985D03*
Y218985D03*
Y213985D03*
Y208985D03*
Y203985D03*
Y198985D03*
Y193985D03*
Y378985D03*
Y373985D03*
Y368985D03*
Y363985D03*
Y358985D03*
Y353985D03*
Y348985D03*
Y343985D03*
Y338985D03*
Y333985D03*
Y328985D03*
Y323985D03*
Y318985D03*
Y313985D03*
Y308985D03*
Y303985D03*
Y298985D03*
Y293985D03*
Y288985D03*
Y418985D03*
Y433985D03*
Y428985D03*
Y423985D03*
Y473985D03*
Y468985D03*
Y463985D03*
Y458985D03*
Y453985D03*
Y448985D03*
Y443985D03*
Y438985D03*
Y413985D03*
Y408985D03*
Y403985D03*
Y398985D03*
Y393985D03*
Y388985D03*
Y383985D03*
Y568985D03*
Y563985D03*
Y558985D03*
Y553985D03*
Y548985D03*
Y543985D03*
Y538985D03*
Y533985D03*
Y528985D03*
Y523985D03*
Y518985D03*
Y513985D03*
Y508985D03*
Y503985D03*
Y498985D03*
Y493985D03*
Y488985D03*
Y483985D03*
Y478985D03*
Y663985D03*
Y658985D03*
Y653985D03*
Y648985D03*
Y643985D03*
Y638985D03*
Y633985D03*
Y628985D03*
Y623985D03*
Y618985D03*
Y613985D03*
Y608985D03*
Y603985D03*
Y598985D03*
Y593985D03*
Y588985D03*
Y583985D03*
Y578985D03*
Y573985D03*
Y758985D03*
Y753985D03*
Y748985D03*
Y743985D03*
Y738985D03*
Y733985D03*
Y728985D03*
Y723985D03*
Y718985D03*
Y713985D03*
Y708985D03*
Y703985D03*
Y698985D03*
Y693985D03*
Y688985D03*
Y683985D03*
Y678985D03*
Y673985D03*
Y668985D03*
Y853985D03*
Y848985D03*
Y843985D03*
Y838985D03*
Y833985D03*
Y828985D03*
Y823985D03*
Y818985D03*
Y813985D03*
Y808985D03*
Y803985D03*
Y798985D03*
Y793985D03*
Y788985D03*
Y783985D03*
Y778985D03*
Y773985D03*
Y768985D03*
Y763985D03*
Y918985D03*
Y913985D03*
Y908985D03*
Y903985D03*
Y898985D03*
Y893985D03*
Y888985D03*
Y883985D03*
Y878985D03*
Y873985D03*
Y868985D03*
Y863985D03*
Y858985D03*
Y948985D03*
Y943985D03*
Y938985D03*
Y933985D03*
Y928985D03*
Y923985D03*
Y1043985D03*
Y1038985D03*
Y1033985D03*
Y1028985D03*
Y1023985D03*
Y1018985D03*
Y1013985D03*
Y1008985D03*
Y1003985D03*
Y998985D03*
Y993985D03*
Y988985D03*
Y983985D03*
Y978985D03*
Y973985D03*
Y968985D03*
Y963985D03*
Y958985D03*
Y953985D03*
Y1143985D03*
Y1138985D03*
Y1133985D03*
Y1128985D03*
Y1123985D03*
Y1118985D03*
Y1113985D03*
Y1108985D03*
Y1103985D03*
Y1098985D03*
Y1093985D03*
Y1088985D03*
Y1083985D03*
Y1078985D03*
Y1073985D03*
Y1068985D03*
Y1063985D03*
Y1058985D03*
Y1053985D03*
Y1048985D03*
Y1238985D03*
Y1233985D03*
Y1228985D03*
Y1223985D03*
Y1218985D03*
Y1213985D03*
Y1208985D03*
Y1203985D03*
Y1198985D03*
Y1193985D03*
Y1188985D03*
Y1183985D03*
Y1178985D03*
Y1173985D03*
Y1168985D03*
Y1163985D03*
Y1158985D03*
Y1153985D03*
Y1148985D03*
Y1288985D03*
Y1293985D03*
Y1298985D03*
Y1303985D03*
Y1308985D03*
Y1313985D03*
Y1318985D03*
Y1323985D03*
Y1328985D03*
Y1333985D03*
Y1283985D03*
Y1278985D03*
Y1273985D03*
Y1268985D03*
Y1263985D03*
Y1258985D03*
Y1253985D03*
Y1248985D03*
Y1243985D03*
Y1348985D03*
Y1353985D03*
Y1358985D03*
Y1363985D03*
Y1368985D03*
Y1373985D03*
Y1378985D03*
Y1383985D03*
Y1388985D03*
Y1393985D03*
Y1398985D03*
Y1403985D03*
Y1408985D03*
Y1413985D03*
Y1418985D03*
Y1423985D03*
Y1428985D03*
Y1338985D03*
Y1343985D03*
Y1448985D03*
Y1443985D03*
Y1433985D03*
Y1438985D03*
X1920000Y1458000D03*
X1917500Y1463500D03*
X1916582Y1513685D03*
X1917031Y1509134D03*
Y1504134D03*
Y1499134D03*
Y1494134D03*
Y1489134D03*
Y1484134D03*
Y1479134D03*
Y1474134D03*
Y1469134D03*
X1926500Y1455000D03*
G54D28*
X159860Y924548D03*
X163860D03*
X257687Y487212D03*
X261687D03*
X1800556Y490630D03*
X1804556D03*
X1874660Y925148D03*
X1878660D03*
G54D14*
X91114Y909791D03*
X85000Y885500D03*
X89000D03*
Y881500D03*
X85000D03*
X89000Y877500D03*
X85000D03*
X89000Y889500D03*
X85000D03*
X89000Y893500D03*
X85000D03*
X81166Y892754D03*
Y888754D03*
X41263Y887025D03*
X48763D03*
X55763D03*
X51263Y894525D03*
X46763Y891525D03*
X178993Y455018D03*
Y451018D03*
X182827Y447764D03*
Y455764D03*
X186827D03*
X182827Y451764D03*
X186827D03*
X182827Y439764D03*
Y443764D03*
X188941Y472055D03*
X153590Y449289D03*
X146590D03*
X149090Y456789D03*
X144590Y453789D03*
X139090Y449289D03*
X168863Y916425D03*
Y920425D03*
X154663Y916425D03*
Y920425D03*
X266690Y479089D03*
Y483089D03*
X252490D03*
Y479089D03*
X666100Y1360800D03*
Y1368700D03*
Y1376600D03*
Y1352900D03*
X658200Y1360800D03*
Y1368700D03*
Y1376600D03*
Y1352900D03*
X666100Y1345000D03*
X658200D03*
X705600Y1360800D03*
Y1352900D03*
Y1345000D03*
Y1376600D03*
Y1368700D03*
X699600Y1408200D03*
Y1392400D03*
Y1400300D03*
X697700Y1345000D03*
Y1360800D03*
Y1368700D03*
Y1376600D03*
X697100Y1384600D03*
X697700Y1352900D03*
X691700Y1408200D03*
Y1400300D03*
X675900D03*
X683800D03*
Y1408200D03*
X675900D03*
X689800Y1352900D03*
Y1384500D03*
Y1376600D03*
X691700Y1392400D03*
X689800Y1368700D03*
Y1360800D03*
X674000D03*
X681900D03*
Y1368700D03*
X674000D03*
X675900Y1392400D03*
X683800D03*
X674000Y1376600D03*
X681900D03*
Y1384500D03*
X674000D03*
Y1352900D03*
X681900D03*
X689800Y1345000D03*
X681900D03*
X674000D03*
X1721762Y458436D03*
Y454436D03*
X1696359Y452707D03*
X1689359D03*
X1691859Y460207D03*
X1687359Y457207D03*
X1681859Y452707D03*
X1725596Y447182D03*
X1729596Y443182D03*
X1725596D03*
X1729596Y455182D03*
X1725596D03*
X1729596Y459182D03*
X1725596D03*
Y451182D03*
X1729596Y447182D03*
Y451182D03*
X1731710Y475473D03*
X1809559Y482507D03*
Y486507D03*
X1795359D03*
Y482507D03*
X1796166Y892754D03*
Y888754D03*
X1804000Y885500D03*
Y881500D03*
X1800000Y885500D03*
Y893500D03*
X1804000D03*
X1800000Y889500D03*
X1804000D03*
X1800000Y877500D03*
X1804000D03*
X1800000Y881500D03*
X1806114Y909791D03*
X1770763Y887025D03*
X1763763D03*
X1766263Y894525D03*
X1761763Y891525D03*
X1756263Y887025D03*
X1883663Y917025D03*
Y921025D03*
X1869463D03*
Y917025D03*
G54D17*
X80709Y1485118D03*
X701181D03*
X1227953D03*
X1848425D03*
G54D29*
X184252Y1445275D03*
Y1466929D03*
X167716Y1445275D03*
Y1466929D03*
X217322Y1445275D03*
Y1466929D03*
X200787Y1445275D03*
Y1466929D03*
X581102Y1445275D03*
Y1466929D03*
X564567Y1445275D03*
Y1466929D03*
X548031Y1445275D03*
Y1466929D03*
X597637Y1445275D03*
Y1466929D03*
X1331496Y1445275D03*
Y1466929D03*
X1314960Y1445275D03*
Y1466929D03*
X1364566Y1445275D03*
Y1466929D03*
X1348031Y1445275D03*
Y1466929D03*
X1711811Y1445275D03*
Y1466929D03*
X1695275Y1445275D03*
Y1466929D03*
X1744881Y1445275D03*
Y1466929D03*
X1728346Y1445275D03*
Y1466929D03*
G54D10*
X59400Y32600D03*
X63374Y1454500D03*
X390757Y1511515D03*
X812347Y17406D03*
X885639Y1511515D03*
X1187163Y158305D03*
X1538001Y1511515D03*
X1869500Y1461500D03*
G54D22*
X173228Y55118D03*
X421653Y94488D03*
X670078Y55118D03*
X1343701D03*
X1592126Y94488D03*
X1840551Y55118D03*
G54D34*
X503248Y715748D03*
X1673917Y262992D03*
G54D31*
X246535Y1320472D03*
X531535D03*
G54D32*
X266535D03*
X511535D03*
G54D30*
X167716Y1495669D03*
X233858D03*
X548031D03*
X614173D03*
X1314960D03*
X1381102D03*
X1695275D03*
X1761417D03*
G54D24*
X173228Y122047D03*
X670079D03*
X1343701Y122046D03*
X1840551D03*
G54D38*
X1104528Y1162257D03*
G54D13*
X69942Y406555D03*
X57675Y851609D03*
X180400Y852300D03*
X202500Y82500D03*
X204075Y398609D03*
X305775Y398909D03*
Y851609D03*
X369086Y1313208D03*
X374086D03*
X379086D03*
X384086D03*
X324086D03*
X329086D03*
X334086D03*
X339086D03*
X344086D03*
X349086D03*
X354086D03*
X359086D03*
X364086D03*
X294086D03*
X299086D03*
X304086D03*
X309086D03*
X319086D03*
X430275Y399351D03*
X429975Y851409D03*
X389086Y1313208D03*
X394086D03*
X554475Y399651D03*
X524236Y1463672D03*
X665475Y399378D03*
X670875Y851409D03*
X594055Y852609D03*
X658200Y1329200D03*
X666100D03*
Y1337100D03*
X658200D03*
X699500Y82500D03*
X705600Y1329200D03*
X697700Y1321300D03*
Y1329200D03*
X689800D03*
Y1321300D03*
X693800Y1313900D03*
Y1306000D03*
X685900D03*
X678000D03*
Y1313900D03*
X685900D03*
X681900Y1321300D03*
X674000D03*
Y1329200D03*
X681900D03*
X693800Y1298000D03*
X685900D03*
X678000D03*
X705600Y1337100D03*
X697700D03*
X689800D03*
X681900D03*
X674000D03*
X826843Y409096D03*
Y404296D03*
Y399496D03*
X822043D03*
Y404296D03*
Y409096D03*
X807643Y408996D03*
Y404196D03*
Y399396D03*
X802843D03*
Y404196D03*
Y408996D03*
X822400Y567100D03*
Y562300D03*
Y557500D03*
X817600D03*
Y562300D03*
Y567100D03*
X803200Y557400D03*
Y562200D03*
Y567000D03*
X798400Y557400D03*
Y562200D03*
Y567000D03*
X853900Y839200D03*
X834470Y944430D03*
X842270Y942411D03*
X796301Y959795D03*
X808300Y1197300D03*
X813100D03*
Y1206900D03*
Y1202100D03*
X808300D03*
Y1206900D03*
X794100Y1197300D03*
X789300D03*
X794100Y1202100D03*
Y1206900D03*
X789300Y1202100D03*
Y1206900D03*
X957500Y842400D03*
X944000D03*
X944500Y1134500D03*
X952500D03*
X974015Y284449D03*
X986614D03*
X974015Y278544D03*
X986614D03*
X974015Y307087D03*
X986614D03*
X1002362D03*
X1014960D03*
X1030709D03*
X1043307D03*
X974015Y312993D03*
X1002362D03*
X1030709D03*
X974015Y301182D03*
X1002362D03*
X1030709D03*
X974015Y290355D03*
X986614Y312993D03*
X1014960D03*
X1043307D03*
X986614Y301182D03*
X1014960D03*
X1043307D03*
X986614Y290355D03*
X1038200Y762300D03*
X1021194Y766883D03*
X1035594Y766983D03*
X1040394D03*
X1021194Y771683D03*
Y776483D03*
X1035594Y776583D03*
Y771783D03*
X1040394D03*
Y776583D03*
X1016394Y766883D03*
Y776483D03*
Y771683D03*
X962000Y842400D03*
X997083Y895935D03*
X986728Y891100D03*
X960500Y1134500D03*
X1065055Y226895D03*
Y231895D03*
Y236895D03*
Y241895D03*
Y221895D03*
X1119877Y408072D03*
Y403272D03*
Y398472D03*
X1124677D03*
Y403272D03*
Y408072D03*
X1100677Y407972D03*
Y403172D03*
Y398372D03*
X1105477D03*
Y403172D03*
Y407972D03*
X1128700Y1206500D03*
X1133500D03*
Y1201700D03*
X1128700D03*
X1133500Y1196900D03*
X1128700D03*
X1109600Y1197100D03*
X1114400D03*
X1109600Y1201900D03*
X1114400D03*
Y1206700D03*
X1109600D03*
X1124612Y1388773D03*
X1130112Y1363273D03*
X1138112D03*
X1132112Y1380773D03*
X1114112Y1363273D03*
X1118112D03*
X1126112D03*
X1110512Y1403273D03*
X1229000Y189500D03*
X1225000Y194000D03*
X1228344Y852351D03*
X1178712Y1372573D03*
X1200962Y1413023D03*
X1209819Y1417377D03*
X1252750Y53650D03*
X1265250D03*
X1274396Y407915D03*
X1252750Y506406D03*
X1265250D03*
X1376963Y53650D03*
X1389463D03*
X1352557Y399595D03*
X1376963Y506406D03*
X1389463D03*
X1352557Y852351D03*
X1501175Y53650D03*
X1513675D03*
X1476769Y399595D03*
X1501175Y506406D03*
X1513675D03*
X1476769Y852351D03*
X1625388Y53650D03*
X1600982Y399595D03*
X1625388Y506406D03*
X1597000Y857500D03*
X1637888Y53650D03*
Y506406D03*
X1749600Y53650D03*
X1762100D03*
X1811700Y59550D03*
X1764168Y405501D03*
X1816375Y399951D03*
X1749600Y506406D03*
X1762100D03*
X1725194Y852351D03*
X1873813Y53650D03*
X1886313D03*
X1820200Y70140D03*
X1885200Y81000D03*
X1871400Y82000D03*
X1873813Y506406D03*
X1886313D03*
X1883200Y534600D03*
X1849407Y852351D03*
X1883100Y984750D03*
G54D18*
X127988Y67319D03*
Y80319D03*
X148050Y20971D03*
X126900Y39500D03*
X150700Y33100D03*
X127988Y520075D03*
Y533075D03*
Y972831D03*
Y985831D03*
X252200Y67319D03*
Y80319D03*
Y520075D03*
Y533075D03*
Y972831D03*
Y985831D03*
X376413Y67319D03*
Y80319D03*
Y520075D03*
Y533075D03*
Y972831D03*
Y985831D03*
X373492Y1317441D03*
Y1322441D03*
Y1327441D03*
Y1332441D03*
X343688Y1317736D03*
Y1322736D03*
Y1327736D03*
Y1332736D03*
X313688D03*
Y1327736D03*
Y1322736D03*
Y1317736D03*
Y1312736D03*
X373492Y1337441D03*
Y1342441D03*
Y1347441D03*
Y1352441D03*
X343688Y1337736D03*
Y1342736D03*
Y1347736D03*
Y1352736D03*
X313688D03*
Y1347736D03*
Y1342736D03*
Y1337736D03*
X500625Y67319D03*
Y80319D03*
Y520075D03*
Y533075D03*
Y972831D03*
Y985831D03*
X505224Y1424156D03*
X624838Y67319D03*
Y80319D03*
Y520075D03*
Y533075D03*
Y972831D03*
Y985831D03*
X657836Y1433318D03*
X749051Y67319D03*
Y80319D03*
Y520075D03*
Y533075D03*
Y972831D03*
Y985831D03*
X855100Y258531D03*
X841000D03*
X826700D03*
X869300D03*
X878740Y655190D03*
Y647190D03*
X932986Y752682D03*
X876255Y818998D03*
X880983Y804420D03*
X936543Y762518D03*
X988341Y563811D03*
X985631Y559671D03*
X984197Y533383D03*
X966861Y772518D03*
X982500Y1217000D03*
Y1209000D03*
X964810Y1421172D03*
X1091089Y520057D03*
X1105262D03*
X1119435D03*
X1133609D03*
X1095026Y527143D03*
X1109199D03*
X1123372D03*
X1091089Y534230D03*
X1105262D03*
X1119435D03*
X1133609D03*
X1095026Y541317D03*
X1109199D03*
X1123372D03*
X1091089Y548403D03*
X1105262D03*
X1119435D03*
X1133609D03*
X1095026Y555490D03*
X1109199D03*
X1123372D03*
X1091089Y562576D03*
X1105262D03*
X1119435D03*
X1133609D03*
X1095026Y569663D03*
X1109199D03*
X1123372D03*
X1091089Y691711D03*
Y705884D03*
Y720057D03*
Y734230D03*
Y748403D03*
Y762577D03*
X1105262Y691711D03*
Y705884D03*
Y720057D03*
Y734230D03*
Y748403D03*
Y762577D03*
X1119435Y691711D03*
Y705884D03*
Y720057D03*
Y734230D03*
Y748403D03*
Y762577D03*
X1133609Y691711D03*
Y705884D03*
Y720057D03*
Y734230D03*
Y748403D03*
Y762577D03*
X1095026Y698797D03*
Y712970D03*
Y727144D03*
Y741317D03*
Y755490D03*
X1109199Y698797D03*
Y712970D03*
Y727144D03*
Y741317D03*
Y755490D03*
X1123372Y698797D03*
Y712970D03*
Y727144D03*
Y741317D03*
Y755490D03*
X1091089Y776750D03*
Y790923D03*
Y805096D03*
Y819270D03*
Y833443D03*
Y847616D03*
X1105262Y776750D03*
Y790923D03*
Y805096D03*
Y819270D03*
Y833443D03*
Y847616D03*
X1119435Y776750D03*
Y790923D03*
Y805096D03*
Y819270D03*
Y833443D03*
Y847616D03*
X1133609Y776750D03*
Y790923D03*
Y805096D03*
Y819270D03*
Y833443D03*
Y847616D03*
X1095026Y769663D03*
Y783836D03*
Y798010D03*
Y812183D03*
Y826356D03*
Y840529D03*
Y854703D03*
X1109199Y769663D03*
Y783836D03*
Y798010D03*
Y812183D03*
Y826356D03*
Y840529D03*
Y854703D03*
X1123372Y769663D03*
Y783836D03*
Y798010D03*
Y812183D03*
Y826356D03*
Y840529D03*
Y854703D03*
X1091089Y861789D03*
Y875962D03*
Y890136D03*
Y904309D03*
Y918482D03*
Y932655D03*
X1105262Y861789D03*
Y875962D03*
Y890136D03*
Y904309D03*
Y918482D03*
Y932655D03*
X1119435Y861789D03*
Y875962D03*
Y890136D03*
Y904309D03*
Y918482D03*
Y932655D03*
X1133609Y861789D03*
Y875962D03*
Y890136D03*
Y904309D03*
Y918482D03*
Y932655D03*
X1095026Y868876D03*
Y883049D03*
Y897222D03*
Y911396D03*
Y925569D03*
Y939742D03*
X1109199Y868876D03*
Y883049D03*
Y897222D03*
Y911396D03*
Y925569D03*
Y939742D03*
X1123372Y868876D03*
Y883049D03*
Y897222D03*
Y911396D03*
Y925569D03*
Y939742D03*
X1101405Y1120040D03*
X1119633D03*
X1108098D03*
X1126326D03*
X1130873Y1490848D03*
Y1495848D03*
X1223730Y1285803D03*
X1230600D03*
X1235600D03*
X1202394D03*
X1197394D03*
X1190524D03*
X1273975Y972831D03*
Y985831D03*
X1398188Y972831D03*
Y985831D03*
X1522400Y972831D03*
Y985831D03*
X1646613Y972831D03*
Y985831D03*
X1808600Y78200D03*
X1803500Y82200D03*
X1795600Y44900D03*
X1817500Y32700D03*
X1814850Y21500D03*
X1770825Y972831D03*
Y985831D03*
X1866700Y512800D03*
X1866500Y507250D03*
X1859300Y524500D03*
X1895038Y972831D03*
Y985831D03*
X1859600Y960250D03*
X1870800Y973100D03*
X1859300Y977500D03*
G54D26*
X168937Y850845D03*
X154737Y854845D03*
Y850845D03*
X168937Y854845D03*
X266764Y417509D03*
Y413509D03*
X252564D03*
Y417509D03*
X581800Y1321200D03*
Y1329100D03*
X589700D03*
Y1321200D03*
X594800Y1313500D03*
X597600Y1321200D03*
Y1329100D03*
X610600Y1313500D03*
Y1305600D03*
Y1297600D03*
X602700Y1313500D03*
Y1305600D03*
Y1297600D03*
X629200Y1329100D03*
X605500Y1321200D03*
X613400D03*
X605500Y1329100D03*
X613400D03*
X621300D03*
X581800Y1337000D03*
X589700D03*
X597600D03*
X629200D03*
X613400D03*
X621300D03*
X605500D03*
X944200Y1083100D03*
X938900Y1103700D03*
X938800Y1109300D03*
X1032361Y1114039D03*
X1021970Y1096850D03*
X982500Y1136500D03*
X986500Y1131500D03*
X982500Y1144500D03*
X1809633Y420927D03*
Y416927D03*
X1795433D03*
Y420927D03*
X1883737Y855445D03*
Y851445D03*
X1869537D03*
Y855445D03*
G54D27*
X163740Y846722D03*
X159740D03*
X257567Y409386D03*
X261567D03*
X1800436Y412804D03*
X1804436D03*
X1874540Y847322D03*
X1878540D03*
G36*
G01X149667Y265962D02*
G02X112734I-18466J-14781D01*
G03X119307Y278426I-29176J23351D01*
G02X143094I11894J-3623D01*
G03X149667Y265962I35749J10887D01*
G37*
G36*
G01Y718718D02*
G02X112734I-18466J-14781D01*
G03X119307Y731182I-29176J23351D01*
G02X143094I11894J-3623D01*
G03X149667Y718718I35749J10887D01*
G37*
G36*
G01Y1171473D02*
G02X112734I-18466J-14781D01*
G03X119307Y1183937I-29176J23351D01*
G02X143094I11894J-3623D01*
G03X149667Y1171473I35749J10887D01*
G37*
G36*
G01X397699Y265962D02*
G02X360766I-18467J-14781D01*
G03X367339Y278426I-29176J23351D01*
G02X391126I11894J-3623D01*
G03X397699Y265962I35749J10887D01*
G37*
G36*
G01Y718718D02*
G02X360766I-18467J-14781D01*
G03X367339Y731182I-29176J23351D01*
G02X391126I11894J-3623D01*
G03X397699Y718718I35749J10887D01*
G37*
G36*
G01Y1171473D02*
G02X360766I-18467J-14781D01*
G03X367339Y1183937I-29176J23351D01*
G02X391126I11894J-3623D01*
G03X397699Y1171473I35749J10887D01*
G37*
G36*
G01X645730Y265962D02*
G02X608797I-18466J-14781D01*
G03X615370Y278426I-29176J23351D01*
G02X639157I11893J-3623D01*
G03X645730Y265962I35749J10887D01*
G37*
G36*
G01Y718718D02*
G02X608797I-18466J-14781D01*
G03X615370Y731182I-29176J23351D01*
G02X639157I11893J-3623D01*
G03X645730Y718718I35749J10887D01*
G37*
G36*
G01Y1171473D02*
G02X608797I-18466J-14781D01*
G03X615370Y1183937I-29176J23351D01*
G02X639157I11893J-3623D01*
G03X645730Y1171473I35749J10887D01*
G37*
G36*
G01X765711Y384859D02*
G02X728778I-18466J-14781D01*
G03X735351Y397323I-29176J23351D01*
G02X759138I11893J-3623D01*
G03X765711Y384859I35749J10887D01*
G37*
G36*
G01Y817930D02*
G02X728778I-18466J-14781D01*
G03X735351Y830394I-29176J23351D01*
G02X759138I11893J-3623D01*
G03X765711Y817930I35749J10887D01*
G37*
G36*
G01X979884Y706906D02*
G02X942951I-18467J-14781D01*
G03X949524Y719370I-29176J23351D01*
G02X973311I11894J-3623D01*
G03X979884Y706906I35749J10887D01*
G37*
G36*
G01Y975410D02*
G02X942951I-18467J-14781D01*
G03X949524Y987874I-29176J23351D01*
G02X973311I11894J-3623D01*
G03X979884Y975410I35749J10887D01*
G37*
G36*
G01X1200356Y384859D02*
G02X1163423I-18467J-14781D01*
G03X1169996Y397323I-29176J23351D01*
G02X1193783I11894J-3623D01*
G03X1200356Y384859I35749J10887D01*
G37*
G36*
G01Y975410D02*
G02X1163423I-18467J-14781D01*
G03X1169996Y987874I-29176J23351D01*
G02X1193783I11894J-3623D01*
G03X1200356Y975410I35749J10887D01*
G37*
G36*
G01X1320337Y265961D02*
G02X1283404I-18467J-14781D01*
G03X1289977Y278425I-29176J23351D01*
G02X1313764I11894J-3623D01*
G03X1320337Y265961I35749J10887D01*
G37*
G36*
G01Y718718D02*
G02X1283404I-18467J-14781D01*
G03X1289977Y731182I-29176J23351D01*
G02X1313764I11894J-3623D01*
G03X1320337Y718718I35749J10887D01*
G37*
G36*
G01Y1171473D02*
G02X1283404I-18467J-14781D01*
G03X1289977Y1183937I-29176J23351D01*
G02X1313764I11894J-3623D01*
G03X1320337Y1171473I35749J10887D01*
G37*
G36*
G01X1568368Y265962D02*
G02X1531435I-18467J-14781D01*
G03X1538008Y278426I-29176J23351D01*
G02X1561795I11894J-3623D01*
G03X1568368Y265962I35749J10887D01*
G37*
G36*
G01Y718718D02*
G02X1531435I-18467J-14781D01*
G03X1538008Y731182I-29176J23351D01*
G02X1561795I11894J-3623D01*
G03X1568368Y718718I35749J10887D01*
G37*
G36*
G01Y1171473D02*
G02X1531435I-18467J-14781D01*
G03X1538008Y1183937I-29176J23351D01*
G02X1561795I11894J-3623D01*
G03X1568368Y1171473I35749J10887D01*
G37*
G36*
G01X1816400Y265961D02*
G02X1779467I-18466J-14781D01*
G03X1786040Y278425I-29176J23351D01*
G02X1809827I11894J-3623D01*
G03X1816400Y265961I35749J10887D01*
G37*
G36*
G01Y718718D02*
G02X1779467I-18466J-14781D01*
G03X1786040Y731182I-29176J23351D01*
G02X1809827I11894J-3623D01*
G03X1816400Y718718I35749J10887D01*
G37*
G36*
G01Y1171473D02*
G02X1779467I-18466J-14781D01*
G03X1786040Y1183937I-29176J23351D01*
G02X1809827I11894J-3623D01*
G03X1816400Y1171473I35749J10887D01*
G37*
%LPC*%
G75*
G54D40*
G01X489037Y-206331D02*
X489911Y-205456D01*
X490566Y-203998D01*
X491003Y-201955D01*
X490566Y-200206D01*
X489693Y-199039D01*
X488164Y-198164D01*
X482269D01*
Y-215664D01*
X489474D01*
X491003Y-214498D01*
X491876Y-212747D01*
X492313Y-210706D01*
X491876Y-208664D01*
X490566Y-206914D01*
X489037Y-206331D01*
X482269D01*
G01X501734Y-215664D02*
Y-203998D01*
G01Y-206331D02*
X502826Y-205164D01*
X503918Y-204289D01*
X505446Y-203998D01*
X506537Y-204289D01*
X507848Y-205164D01*
G01X517706Y-220914D02*
X519016Y-221497D01*
X520763Y-220914D01*
X521854Y-219748D01*
X522728Y-218289D01*
X524037Y-213623D01*
X526876Y-203998D01*
G01X519889D02*
X524037Y-213623D01*
G01X543284Y-205456D02*
X541756Y-204289D01*
X540446Y-203998D01*
X538699Y-204581D01*
X537389Y-205747D01*
X536516Y-207789D01*
X536297Y-209831D01*
X536516Y-211873D01*
X537389Y-213623D01*
X538699Y-215081D01*
X540446Y-215664D01*
X541974Y-215081D01*
X543284Y-213914D01*
G01X554016Y-207789D02*
X561003D01*
X560348Y-205747D01*
X559256Y-204581D01*
X557728Y-203998D01*
X556199Y-204289D01*
X554889Y-205164D01*
X554016Y-207206D01*
X553579Y-208956D01*
Y-210706D01*
X554016Y-212456D01*
X555108Y-214206D01*
X556418Y-215372D01*
X557946Y-215664D01*
X559474Y-215081D01*
X561003Y-213331D01*
G01X597094Y-199623D02*
X595784Y-198747D01*
X594256Y-198164D01*
X592509D01*
X590544Y-199039D01*
X589016Y-200497D01*
X587924Y-202248D01*
X587051Y-205164D01*
X586832Y-207789D01*
X587269Y-210414D01*
X587924Y-212164D01*
X589234Y-213914D01*
X590763Y-215081D01*
X592291Y-215664D01*
X593819D01*
X595348Y-215081D01*
X596658Y-214206D01*
X597750Y-213040D01*
G01X613721Y-215664D02*
Y-203998D01*
G01Y-206039D02*
X612848Y-204873D01*
X611537Y-204289D01*
X610009Y-203998D01*
X608481Y-204581D01*
X607171Y-205747D01*
X606297Y-207497D01*
X605861Y-209831D01*
X606297Y-212164D01*
X607171Y-213914D01*
X608481Y-215081D01*
X610009Y-215664D01*
X611537Y-215372D01*
X612848Y-214498D01*
X613721Y-213331D01*
G01X623579Y-215664D02*
Y-203998D01*
G01Y-206914D02*
X624453Y-205456D01*
X625763Y-204289D01*
X627509Y-203998D01*
X629037Y-204289D01*
X630348Y-205456D01*
X631003Y-207497D01*
Y-215664D01*
G01X640206Y-220914D02*
X641516Y-221497D01*
X643263Y-220914D01*
X644354Y-219748D01*
X645228Y-218289D01*
X646537Y-213623D01*
X649376Y-203998D01*
G01X642389D02*
X646537Y-213623D01*
G01X662291Y-215664D02*
X660981Y-215372D01*
X659671Y-214206D01*
X658797Y-212164D01*
X658361Y-209831D01*
X658797Y-207497D01*
X659671Y-205456D01*
X660981Y-204289D01*
X662291Y-203998D01*
X663601Y-204289D01*
X664911Y-205456D01*
X665784Y-207497D01*
X666003Y-209831D01*
X665784Y-212164D01*
X664911Y-214206D01*
X663601Y-215372D01*
X662291Y-215664D01*
G01X676079D02*
Y-203998D01*
G01Y-206914D02*
X676953Y-205456D01*
X678263Y-204289D01*
X680009Y-203998D01*
X681537Y-204289D01*
X682848Y-205456D01*
X683503Y-207497D01*
Y-215664D01*
G01X710424D02*
Y-198164D01*
X715883D01*
X717629Y-199039D01*
X718721Y-200206D01*
X719158Y-202539D01*
X718721Y-204873D01*
X717411Y-206331D01*
X715883Y-207206D01*
X710424D01*
G01X715883D02*
X719158Y-215664D01*
G01X732291Y-216247D02*
X731854Y-215956D01*
Y-215372D01*
X732291Y-215081D01*
X732728Y-215372D01*
Y-215956D01*
X732291Y-216247D01*
G01X744988Y-215664D02*
Y-198164D01*
X749354D01*
X751101Y-199039D01*
X752411Y-200206D01*
X753503Y-201955D01*
X754376Y-203998D01*
X754594Y-206914D01*
X754376Y-209831D01*
X753503Y-211873D01*
X752411Y-213623D01*
X751101Y-214789D01*
X749354Y-215664D01*
X744988D01*
G01X762924D02*
Y-198164D01*
X768164D01*
X769911Y-199039D01*
X771221Y-201081D01*
X771658Y-203414D01*
X771221Y-205747D01*
X770129Y-207497D01*
X768164Y-208373D01*
X762924D01*
G01X786537Y-206331D02*
X787411Y-205456D01*
X788066Y-203998D01*
X788503Y-201955D01*
X788066Y-200206D01*
X787193Y-199039D01*
X785664Y-198164D01*
X779769D01*
Y-215664D01*
X786974D01*
X788503Y-214498D01*
X789376Y-212747D01*
X789813Y-210706D01*
X789376Y-208664D01*
X788066Y-206914D01*
X786537Y-206331D01*
X779769D01*
G01X595364Y-170664D02*
Y-153164D01*
X601041Y-167747D01*
X606718Y-153164D01*
Y-170664D01*
G01X618541D02*
X617231Y-170372D01*
X615921Y-169206D01*
X615047Y-167164D01*
X614611Y-164831D01*
X615047Y-162497D01*
X615921Y-160456D01*
X617231Y-159289D01*
X618541Y-158998D01*
X619851Y-159289D01*
X621161Y-160456D01*
X622034Y-162497D01*
X622253Y-164831D01*
X622034Y-167164D01*
X621161Y-169206D01*
X619851Y-170372D01*
X618541Y-170664D01*
G01X639971Y-153164D02*
Y-170664D01*
G01Y-168040D02*
X639098Y-169498D01*
X637787Y-170372D01*
X636259Y-170664D01*
X634513Y-170081D01*
X633203Y-168623D01*
X632329Y-166873D01*
X632111Y-164831D01*
X632329Y-162789D01*
X633203Y-161039D01*
X634513Y-159581D01*
X636259Y-158998D01*
X637787Y-159289D01*
X638879Y-159873D01*
X639971Y-161039D01*
G01X650266Y-162789D02*
X657253D01*
X656598Y-160747D01*
X655506Y-159581D01*
X653978Y-158998D01*
X652449Y-159289D01*
X651139Y-160164D01*
X650266Y-162206D01*
X649829Y-163956D01*
Y-165706D01*
X650266Y-167456D01*
X651358Y-169206D01*
X652668Y-170372D01*
X654196Y-170664D01*
X655724Y-170081D01*
X657253Y-168331D01*
G01X671041Y-170664D02*
Y-153164D01*
G01X839441Y-215664D02*
Y-198164D01*
X836821Y-201664D01*
G01Y-215664D02*
X842061D01*
G01X852793Y-208373D02*
X854321Y-206331D01*
X855631Y-205164D01*
X857378Y-204581D01*
X858906Y-205164D01*
X859998Y-206331D01*
X860871Y-208081D01*
X861089Y-210122D01*
X860871Y-211873D01*
X859998Y-213623D01*
X858687Y-215081D01*
X857159Y-215664D01*
X855413Y-215081D01*
X853884Y-213331D01*
X853011Y-210706D01*
X852793Y-207789D01*
X853229Y-203998D01*
X853884Y-201955D01*
X854976Y-199914D01*
X856504Y-198456D01*
X858033Y-198164D01*
X859561Y-198747D01*
X860653Y-200206D01*
G01X869638Y-212164D02*
X870947Y-214206D01*
X872694Y-215372D01*
X874659Y-215664D01*
X876406Y-215372D01*
X878153Y-213914D01*
X879244Y-212164D01*
X879463Y-210414D01*
X879026Y-208373D01*
X877498Y-206914D01*
X875969Y-206331D01*
X874004D01*
G01X875969D02*
X877279Y-205456D01*
X878371Y-203998D01*
X878808Y-202248D01*
X878371Y-200497D01*
X877279Y-199039D01*
X875314Y-198164D01*
X873349Y-198456D01*
X871384Y-199623D01*
G01X891941Y-215664D02*
Y-198164D01*
X889321Y-201664D01*
G01Y-215664D02*
X894561D01*
G01X909004D02*
X909441Y-211873D01*
X910096Y-208664D01*
X910969Y-205747D01*
X912061Y-202539D01*
X913808Y-198164D01*
X905074D01*
G01X826324Y-170664D02*
Y-153164D01*
X831564D01*
X833311Y-154039D01*
X834621Y-156081D01*
X835058Y-158414D01*
X834621Y-160747D01*
X833529Y-162497D01*
X831564Y-163373D01*
X826324D01*
G01X852994Y-154623D02*
X851684Y-153747D01*
X850156Y-153164D01*
X848409D01*
X846444Y-154039D01*
X844916Y-155497D01*
X843824Y-157248D01*
X842951Y-160164D01*
X842732Y-162789D01*
X843169Y-165414D01*
X843824Y-167164D01*
X845134Y-168914D01*
X846663Y-170081D01*
X848191Y-170664D01*
X849719D01*
X851248Y-170081D01*
X852558Y-169206D01*
X853650Y-168040D01*
G01X867437Y-161331D02*
X868311Y-160456D01*
X868966Y-158998D01*
X869403Y-156955D01*
X868966Y-155206D01*
X868093Y-154039D01*
X866564Y-153164D01*
X860669D01*
Y-170664D01*
X867874D01*
X869403Y-169498D01*
X870276Y-167747D01*
X870713Y-165706D01*
X870276Y-163664D01*
X868966Y-161914D01*
X867437Y-161331D01*
X860669D01*
G01X876641Y-176497D02*
X889741D01*
G01X895669Y-170664D02*
Y-153164D01*
X905713Y-170664D01*
Y-153164D01*
G01X918191Y-170664D02*
X916444Y-170372D01*
X914916Y-169206D01*
X913606Y-167456D01*
X912732Y-165414D01*
X912296Y-163081D01*
Y-160747D01*
X912732Y-158414D01*
X913606Y-156372D01*
X914916Y-154623D01*
X916444Y-153456D01*
X918191Y-153164D01*
X919937Y-153456D01*
X921466Y-154623D01*
X922776Y-156372D01*
X923650Y-158414D01*
X924086Y-160747D01*
Y-163081D01*
X923650Y-165414D01*
X922776Y-167456D01*
X921466Y-169206D01*
X919937Y-170372D01*
X918191Y-170664D01*
G01X1000741Y-215664D02*
Y-198164D01*
X998121Y-201664D01*
G01Y-215664D02*
X1003361D01*
G01X969032Y-153164D02*
X974491Y-170664D01*
X979950Y-153164D01*
G01X996358Y-170664D02*
X987624D01*
Y-153164D01*
X996358D01*
G01X992864Y-161622D02*
X987624D01*
G01X1005124Y-170664D02*
Y-153164D01*
X1010583D01*
X1012329Y-154039D01*
X1013421Y-155206D01*
X1013858Y-157539D01*
X1013421Y-159873D01*
X1012111Y-161331D01*
X1010583Y-162206D01*
X1005124D01*
G01X1010583D02*
X1013858Y-170664D01*
G01X1026991Y-171247D02*
X1026554Y-170956D01*
Y-170372D01*
X1026991Y-170081D01*
X1027428Y-170372D01*
Y-170956D01*
X1026991Y-171247D01*
G01X1102574Y-198164D02*
Y-215664D01*
X1111308D01*
G01X1120293Y-201081D02*
X1121603Y-199331D01*
X1123131Y-198456D01*
X1124878Y-198164D01*
X1127061Y-198747D01*
X1128589Y-200206D01*
X1129026Y-201955D01*
X1128808Y-203706D01*
X1127934Y-205164D01*
X1123568Y-208081D01*
X1121603Y-210122D01*
X1120293Y-213040D01*
X1119856Y-215664D01*
X1129026D01*
G01X1143251Y-206914D02*
X1147618D01*
Y-212164D01*
X1146308Y-213914D01*
X1144779Y-215081D01*
X1142596Y-215664D01*
X1140413Y-215081D01*
X1138884Y-213914D01*
X1137574Y-212164D01*
X1136701Y-210122D01*
X1136264Y-207789D01*
Y-205747D01*
X1136701Y-203998D01*
X1137574Y-201955D01*
X1138884Y-200206D01*
X1140194Y-199039D01*
X1141941Y-198164D01*
X1143469D01*
X1145216Y-198747D01*
X1146526Y-199914D01*
G01X1154419Y-215664D02*
Y-198164D01*
X1164463Y-215664D01*
Y-198164D01*
G01X1172138Y-215664D02*
Y-198164D01*
X1176504D01*
X1178251Y-199039D01*
X1179561Y-200206D01*
X1180653Y-201955D01*
X1181526Y-203998D01*
X1181744Y-206914D01*
X1181526Y-209831D01*
X1180653Y-211873D01*
X1179561Y-213623D01*
X1178251Y-214789D01*
X1176504Y-215664D01*
X1172138D01*
G01X1102574Y-153164D02*
Y-170664D01*
X1111308D01*
G01X1128371D02*
Y-158998D01*
G01Y-161039D02*
X1127498Y-159873D01*
X1126187Y-159289D01*
X1124659Y-158998D01*
X1123131Y-159581D01*
X1121821Y-160747D01*
X1120947Y-162497D01*
X1120511Y-164831D01*
X1120947Y-167164D01*
X1121821Y-168914D01*
X1123131Y-170081D01*
X1124659Y-170664D01*
X1126187Y-170372D01*
X1127498Y-169498D01*
X1128371Y-168331D01*
G01X1137356Y-175914D02*
X1138666Y-176497D01*
X1140413Y-175914D01*
X1141504Y-174748D01*
X1142378Y-173289D01*
X1143687Y-168623D01*
X1146526Y-158998D01*
G01X1139539D02*
X1143687Y-168623D01*
G01X1156166Y-162789D02*
X1163153D01*
X1162498Y-160747D01*
X1161406Y-159581D01*
X1159878Y-158998D01*
X1158349Y-159289D01*
X1157039Y-160164D01*
X1156166Y-162206D01*
X1155729Y-163956D01*
Y-165706D01*
X1156166Y-167456D01*
X1157258Y-169206D01*
X1158568Y-170372D01*
X1160096Y-170664D01*
X1161624Y-170081D01*
X1163153Y-168331D01*
G01X1173884Y-170664D02*
Y-158998D01*
G01Y-161331D02*
X1174976Y-160164D01*
X1176068Y-159289D01*
X1177596Y-158998D01*
X1178687Y-159289D01*
X1179998Y-160164D01*
G01X1244688Y-170664D02*
Y-153164D01*
X1249054D01*
X1250801Y-154039D01*
X1252111Y-155206D01*
X1253203Y-156955D01*
X1254076Y-158998D01*
X1254294Y-161914D01*
X1254076Y-164831D01*
X1253203Y-166873D01*
X1252111Y-168623D01*
X1250801Y-169789D01*
X1249054Y-170664D01*
X1244688D01*
G01X1263716Y-162789D02*
X1270703D01*
X1270048Y-160747D01*
X1268956Y-159581D01*
X1267428Y-158998D01*
X1265899Y-159289D01*
X1264589Y-160164D01*
X1263716Y-162206D01*
X1263279Y-163956D01*
Y-165706D01*
X1263716Y-167456D01*
X1264808Y-169206D01*
X1266118Y-170372D01*
X1267646Y-170664D01*
X1269174Y-170081D01*
X1270703Y-168331D01*
G01X1281216Y-168623D02*
X1282308Y-169789D01*
X1283836Y-170664D01*
X1285146D01*
X1286456Y-170081D01*
X1287329Y-169206D01*
X1287766Y-168040D01*
X1287548Y-166289D01*
X1286674Y-165414D01*
X1282744Y-163664D01*
X1281871Y-161622D01*
X1282308Y-160164D01*
X1283181Y-159289D01*
X1284491Y-158998D01*
X1285801Y-159289D01*
X1287111Y-160164D01*
G01X1301991Y-158998D02*
Y-170664D01*
G01Y-154331D02*
X1301554Y-154039D01*
Y-153456D01*
X1301991Y-153164D01*
X1302428Y-153456D01*
Y-154039D01*
X1301991Y-154331D01*
G01X1316434Y-175039D02*
X1317963Y-176206D01*
X1319709Y-176497D01*
X1321237Y-176206D01*
X1322548Y-174748D01*
X1323421Y-172706D01*
Y-158998D01*
G01Y-161331D02*
X1322548Y-160164D01*
X1321237Y-159289D01*
X1319709Y-158998D01*
X1317963Y-159581D01*
X1316871Y-160747D01*
X1315997Y-162789D01*
X1315561Y-164831D01*
X1315779Y-166581D01*
X1316653Y-168623D01*
X1317963Y-170081D01*
X1319709Y-170664D01*
X1321019Y-170372D01*
X1322548Y-169206D01*
X1323421Y-168040D01*
G01X1333279Y-170664D02*
Y-158998D01*
G01Y-161914D02*
X1334153Y-160456D01*
X1335463Y-159289D01*
X1337209Y-158998D01*
X1338737Y-159289D01*
X1340048Y-160456D01*
X1340703Y-162497D01*
Y-170664D01*
G01X1351216Y-162789D02*
X1358203D01*
X1357548Y-160747D01*
X1356456Y-159581D01*
X1354928Y-158998D01*
X1353399Y-159289D01*
X1352089Y-160164D01*
X1351216Y-162206D01*
X1350779Y-163956D01*
Y-165706D01*
X1351216Y-167456D01*
X1352308Y-169206D01*
X1353618Y-170372D01*
X1355146Y-170664D01*
X1356674Y-170081D01*
X1358203Y-168331D01*
G01X1368934Y-170664D02*
Y-158998D01*
G01Y-161331D02*
X1370026Y-160164D01*
X1371118Y-159289D01*
X1372646Y-158998D01*
X1373737Y-159289D01*
X1375048Y-160164D01*
G01X1266991Y-215664D02*
X1265244Y-215372D01*
X1263716Y-214206D01*
X1262406Y-212456D01*
X1261532Y-210414D01*
X1261096Y-208081D01*
Y-205747D01*
X1261532Y-203414D01*
X1262406Y-201372D01*
X1263716Y-199623D01*
X1265244Y-198456D01*
X1266991Y-198164D01*
X1268737Y-198456D01*
X1270266Y-199623D01*
X1271576Y-201372D01*
X1272450Y-203414D01*
X1272886Y-205747D01*
Y-208081D01*
X1272450Y-210414D01*
X1271576Y-212456D01*
X1270266Y-214206D01*
X1268737Y-215372D01*
X1266991Y-215664D01*
G01X1268737Y-210997D02*
X1271358Y-215664D01*
G01X1279688Y-198164D02*
Y-210706D01*
X1280561Y-213331D01*
X1282308Y-215081D01*
X1284491Y-215664D01*
X1286674Y-215081D01*
X1288421Y-213331D01*
X1289294Y-210706D01*
Y-198164D01*
G01X1299371D02*
X1304611D01*
G01X1301991D02*
Y-215664D01*
G01X1299371D02*
X1304611D01*
G01X1314469D02*
Y-198164D01*
X1324513Y-215664D01*
Y-198164D01*
G01X1341794Y-199623D02*
X1340484Y-198747D01*
X1338956Y-198164D01*
X1337209D01*
X1335244Y-199039D01*
X1333716Y-200497D01*
X1332624Y-202248D01*
X1331751Y-205164D01*
X1331532Y-207789D01*
X1331969Y-210414D01*
X1332624Y-212164D01*
X1333934Y-213914D01*
X1335463Y-215081D01*
X1336991Y-215664D01*
X1338519D01*
X1340048Y-215081D01*
X1341358Y-214206D01*
X1342450Y-213040D01*
G01X1354491Y-215664D02*
Y-207789D01*
X1350124Y-198164D01*
G01X1358858D02*
X1354491Y-207789D01*
G01X1415691Y-198164D02*
X1413944Y-198747D01*
X1412634Y-200206D01*
X1411761Y-201955D01*
X1411106Y-204289D01*
X1410888Y-206914D01*
X1411106Y-209539D01*
X1411761Y-211873D01*
X1412634Y-213623D01*
X1413944Y-215081D01*
X1415691Y-215664D01*
X1417437Y-215081D01*
X1418748Y-213623D01*
X1419621Y-211873D01*
X1420276Y-209539D01*
X1420494Y-206914D01*
X1420276Y-204289D01*
X1419621Y-201955D01*
X1418748Y-200206D01*
X1417437Y-198747D01*
X1415691Y-198164D01*
G01X1429043Y-208373D02*
X1430571Y-206331D01*
X1431881Y-205164D01*
X1433628Y-204581D01*
X1435156Y-205164D01*
X1436248Y-206331D01*
X1437121Y-208081D01*
X1437339Y-210122D01*
X1437121Y-211873D01*
X1436248Y-213623D01*
X1434937Y-215081D01*
X1433409Y-215664D01*
X1431663Y-215081D01*
X1430134Y-213331D01*
X1429261Y-210706D01*
X1429043Y-207789D01*
X1429479Y-203998D01*
X1430134Y-201955D01*
X1431226Y-199914D01*
X1432754Y-198456D01*
X1434283Y-198164D01*
X1435811Y-198747D01*
X1436903Y-200206D01*
G01X1446761Y-216247D02*
X1454621Y-198164D01*
G01X1468191D02*
X1466444Y-198747D01*
X1465134Y-200206D01*
X1464261Y-201955D01*
X1463606Y-204289D01*
X1463388Y-206914D01*
X1463606Y-209539D01*
X1464261Y-211873D01*
X1465134Y-213623D01*
X1466444Y-215081D01*
X1468191Y-215664D01*
X1469937Y-215081D01*
X1471248Y-213623D01*
X1472121Y-211873D01*
X1472776Y-209539D01*
X1472994Y-206914D01*
X1472776Y-204289D01*
X1472121Y-201955D01*
X1471248Y-200206D01*
X1469937Y-198747D01*
X1468191Y-198164D01*
G01X1481979Y-213623D02*
X1483508Y-215081D01*
X1485254Y-215664D01*
X1487001Y-215081D01*
X1488529Y-213331D01*
X1489621Y-210706D01*
X1490058Y-208081D01*
Y-204873D01*
X1489621Y-202248D01*
X1488529Y-199914D01*
X1487219Y-198747D01*
X1485691Y-198164D01*
X1483944Y-198747D01*
X1482634Y-199914D01*
X1481761Y-201664D01*
X1481324Y-203998D01*
X1481761Y-206039D01*
X1482853Y-208081D01*
X1484163Y-209248D01*
X1485691Y-209539D01*
X1487437Y-208956D01*
X1488748Y-207497D01*
X1490058Y-204873D01*
G01X1499261Y-216247D02*
X1507121Y-198164D01*
G01X1516543Y-201081D02*
X1517853Y-199331D01*
X1519381Y-198456D01*
X1521128Y-198164D01*
X1523311Y-198747D01*
X1524839Y-200206D01*
X1525276Y-201955D01*
X1525058Y-203706D01*
X1524184Y-205164D01*
X1519818Y-208081D01*
X1517853Y-210122D01*
X1516543Y-213040D01*
X1516106Y-215664D01*
X1525276D01*
G01X1538191Y-198164D02*
X1536444Y-198747D01*
X1535134Y-200206D01*
X1534261Y-201955D01*
X1533606Y-204289D01*
X1533388Y-206914D01*
X1533606Y-209539D01*
X1534261Y-211873D01*
X1535134Y-213623D01*
X1536444Y-215081D01*
X1538191Y-215664D01*
X1539937Y-215081D01*
X1541248Y-213623D01*
X1542121Y-211873D01*
X1542776Y-209539D01*
X1542994Y-206914D01*
X1542776Y-204289D01*
X1542121Y-201955D01*
X1541248Y-200206D01*
X1539937Y-198747D01*
X1538191Y-198164D01*
G01X1555691Y-215664D02*
Y-198164D01*
X1553071Y-201664D01*
G01Y-215664D02*
X1558311D01*
G01X1572754D02*
X1573191Y-211873D01*
X1573846Y-208664D01*
X1574719Y-205747D01*
X1575811Y-202539D01*
X1577558Y-198164D01*
X1568824D01*
G01X1463388Y-170664D02*
Y-153164D01*
X1467754D01*
X1469501Y-154039D01*
X1470811Y-155206D01*
X1471903Y-156955D01*
X1472776Y-158998D01*
X1472994Y-161914D01*
X1472776Y-164831D01*
X1471903Y-166873D01*
X1470811Y-168623D01*
X1469501Y-169789D01*
X1467754Y-170664D01*
X1463388D01*
G01X1489621D02*
Y-158998D01*
G01Y-161039D02*
X1488748Y-159873D01*
X1487437Y-159289D01*
X1485909Y-158998D01*
X1484381Y-159581D01*
X1483071Y-160747D01*
X1482197Y-162497D01*
X1481761Y-164831D01*
X1482197Y-167164D01*
X1483071Y-168914D01*
X1484381Y-170081D01*
X1485909Y-170664D01*
X1487437Y-170372D01*
X1488748Y-169498D01*
X1489621Y-168331D01*
G01X1503191Y-153164D02*
Y-170664D01*
G01X1500134Y-158998D02*
X1506248D01*
G01X1517416Y-162789D02*
X1524403D01*
X1523748Y-160747D01*
X1522656Y-159581D01*
X1521128Y-158998D01*
X1519599Y-159289D01*
X1518289Y-160164D01*
X1517416Y-162206D01*
X1516979Y-163956D01*
Y-165706D01*
X1517416Y-167456D01*
X1518508Y-169206D01*
X1519818Y-170372D01*
X1521346Y-170664D01*
X1522874Y-170081D01*
X1524403Y-168331D01*
G54D39*
G01X466941Y-145664D02*
Y-225664D01*
G01D02*
X1593241D01*
G01X462941Y-129664D02*
G02I-12000J0D01*
G01X457791D02*
G02I-6850J0D01*
G01X450941Y-145664D02*
Y-113664D01*
G01X466941Y-129664D02*
X434941D01*
G01X466941Y-145664D02*
X1593241D01*
G01X466941Y-181164D02*
X1593241D01*
G01X805741Y-145664D02*
Y-225664D01*
G01X943241Y-145664D02*
Y-225664D01*
G01X1058241Y-145664D02*
Y-225664D01*
G01X1225741Y-145664D02*
Y-225664D01*
G01X1395741Y-145664D02*
Y-225664D01*
G01X1593241Y-145664D02*
Y-225664D01*
G01X1621241Y-129664D02*
G02I-12000J0D01*
G01X1616091D02*
G02I-6850J0D01*
G01X1609241Y-145664D02*
Y-113664D01*
G01X1625241Y-129664D02*
X1593241D01*
M02*
